FILE_TYPE = MACRO_DRAWING;
SET COLOR_WIRE YELLOW;
SET COLOR_PROP ORANGE;
SET COLOR_DOT WHITE;
SET COLOR_ARC YELLOW;
SET COLOR_BODY GREEN;
SET COLOR_NOTE PURPLE;
SET PROP_DISPLAY VALUE;
SET PAGE_NUMBER P476;
FORCEADD VCC15..1
(1600 -6125);
FORCEPROP 3 LASTPIN (1600 -6175) SIG_NAME P0V9_CPU0_RT_2D\g
J 0
(1610 -6165);
DISPLAY 0.659574 (1610 -6165);
PAINT MONO (1610 -6165);
DISPLAY INVISIBLE (1610 -6165);
FORCEPROP 1 LAST HDL_POWER P0V9_CPU0_RT_2D
J 1
(1600 -6075);
DISPLAY 0.617021 (1600 -6075);
PAINT GREEN (1600 -6075);
FORCEPROP 2 LAST CDS_LIB pure_quanta_power
J 0
(1600 -6125);
PAINT MONO (1600 -6125);
DISPLAY INVISIBLE (1600 -6125);
FORCEPROP 2 LAST BOM_COST VR_DIMM 
J 0
(1600 -6025);
DISPLAY 0.680851 (1600 -6025);
DISPLAY INVISIBLE (1600 -6025);
FORCEPROP 1 LAST PATH I1
J 0
(1650 -6100);
DISPLAY 0.872340 (1650 -6100);
PAINT AQUA (1650 -6100);
DISPLAY INVISIBLE (1650 -6100);
FORCEADD Q_INDUCTOR..1
(1150 -5450);
FORCEPROP 1 LAST LOCATION PL6504
J 0
(1025 -5290);
DISPLAY 0.723404 (1025 -5290);
PAINT GREEN (1025 -5290);
FORCEPROP 2 LAST SEC 1
J 0
(1025 -5150);
DISPLAY 0.680851 (1025 -5150);
PAINT MONO (1025 -5150);
DISPLAY INVISIBLE (1025 -5150);
FORCEPROP 2 LASTPIN (1050 -5475) $PN 1
J 2
(1040 -5465);
DISPLAY 0.680851 (1040 -5465);
PAINT MONO (1040 -5465);
FORCEPROP 2 LASTPIN (1250 -5475) $PN 2
J 0
(1260 -5465);
DISPLAY 0.680851 (1260 -5465);
PAINT MONO (1260 -5465);
FORCEPROP 2 LAST VALUE 100NH/16A
J 0
(1025 -5200);
DISPLAY 1.021277 (1025 -5200);
FORCEPROP 1 LAST MATERIAL IND
J 0
(1025 -5395);
DISPLAY 0.723404 (1025 -5395);
PAINT GREEN (1025 -5395);
FORCEPROP 2 LAST PACK_TYPE SMLF
J 0
(1025 -5250);
DISPLAY 1.021277 (1025 -5250);
FORCEPROP 2 LAST CDS_LIB pure_quanta
J 0
(1150 -5450);
DISPLAY INVISIBLE (1150 -5450);
FORCEPROP 2 LAST SEC_TYPE SMLF
J 0
(1025 -5150);
DISPLAY 1.021277 (1025 -5150);
DISPLAY INVISIBLE (1025 -5150);
FORCEPROP 1 LAST NEEDS_NO_SIZE TRUE
J 0
(1150 -5450);
DISPLAY 0.468085 (1150 -5450);
PAINT GREEN (1150 -5450);
DISPLAY INVISIBLE (1150 -5450);
FORCEPROP 1 LAST PART_NUMBER CV+10G0MZ04
J 0
(1025 -5340);
DISPLAY 0.723404 (1025 -5340);
PAINT GREEN (1025 -5340);
DISPLAY INVISIBLE (1025 -5340);
FORCEPROP 1 LAST PATH I182
J 0
(1225 -5395);
DISPLAY 0.723404 (1225 -5395);
PAINT GREEN (1225 -5395);
DISPLAY INVISIBLE (1225 -5395);
FORCEADD Q_RES..2
(-6450 -4650);
FORCEPROP 1 LAST LOCATION PR6550
J 0
(-6405 -4525);
DISPLAY 0.787234 (-6405 -4525);
FORCEPROP 2 LAST SEC 1
J 0
(-6400 -4425);
DISPLAY 0.680851 (-6400 -4425);
PAINT MONO (-6400 -4425);
DISPLAY INVISIBLE (-6400 -4425);
FORCEPROP 1 LASTPIN (-6450 -4550) $PN 1
J 0
(-6445 -4588);
DISPLAY 0.787234 (-6445 -4588);
PAINT MONO (-6445 -4588);
FORCEPROP 1 LASTPIN (-6450 -4750) $PN 2
J 0
(-6445 -4740);
DISPLAY 0.787234 (-6445 -4740);
PAINT MONO (-6445 -4740);
FORCEPROP 1 LAST TOLERANCE 5%
J 0
(-6405 -4625);
DISPLAY 0.638298 (-6405 -4625);
FORCEPROP 1 LAST MATERIAL CHIP
J 0
(-6410 -4725);
DISPLAY 0.638298 (-6410 -4725);
FORCEPROP 1 LAST PACK_TYPE 0402LF
J 0
(-6410 -4825);
DISPLAY 0.638298 (-6410 -4825);
FORCEPROP 1 LAST VALUE 0
J 0
(-6405 -4575);
DISPLAY 0.638298 (-6405 -4575);
FORCEPROP 1 LAST WATTAGE 1/16W
J 0
(-6410 -4675);
DISPLAY 0.638298 (-6410 -4675);
FORCEPROP 2 LAST CDS_LIB pure_quanta
J 0
(-6450 -4650);
DISPLAY INVISIBLE (-6450 -4650);
FORCEPROP 2 LAST SEC_TYPE 0402LF
J 0
(-6400 -4425);
DISPLAY 1.021277 (-6400 -4425);
DISPLAY INVISIBLE (-6400 -4425);
FORCEPROP 1 LAST PART_NUMBER CS00002JB13
J 0
(-6410 -4775);
DISPLAY 0.638298 (-6410 -4775);
DISPLAY INVISIBLE (-6410 -4775);
FORCEPROP 1 LAST PATH I183
J 0
(-6400 -4475);
DISPLAY 0.978723 (-6400 -4475);
PAINT WHITE (-6400 -4475);
DISPLAY INVISIBLE (-6400 -4475);
FORCEADD UNIVERSAL_POWER..1
(-6450 -4350);
FORCEPROP 3 LASTPIN (-6450 -4400) SIG_NAME P5V_AUX\g
J 0
(-6440 -4390);
DISPLAY 0.659574 (-6440 -4390);
PAINT MONO (-6440 -4390);
DISPLAY INVISIBLE (-6440 -4390);
FORCEPROP 1 LAST HDL_POWER P5V_AUX
J 1
(-6450 -4300);
DISPLAY 0.872340 (-6450 -4300);
PAINT GREEN (-6450 -4300);
FORCEPROP 2 LAST CDS_LIB pure_quanta_power
J 0
(-6450 -4350);
DISPLAY INVISIBLE (-6450 -4350);
FORCEPROP 1 LAST PATH I184
J 0
(-6400 -4325);
DISPLAY 0.872340 (-6400 -4325);
PAINT AQUA (-6400 -4325);
DISPLAY INVISIBLE (-6400 -4325);
FORCEADD Q_RES..2
(-5550 -4650);
FORCEPROP 1 LAST LOCATION PR6551
J 0
(-5505 -4525);
DISPLAY 0.787234 (-5505 -4525);
FORCEPROP 2 LAST SEC 1
J 0
(-5500 -4425);
DISPLAY 0.680851 (-5500 -4425);
PAINT MONO (-5500 -4425);
DISPLAY INVISIBLE (-5500 -4425);
FORCEPROP 1 LASTPIN (-5550 -4550) $PN 1
J 0
(-5545 -4588);
DISPLAY 0.787234 (-5545 -4588);
PAINT MONO (-5545 -4588);
FORCEPROP 1 LASTPIN (-5550 -4750) $PN 2
J 0
(-5545 -4740);
DISPLAY 0.787234 (-5545 -4740);
PAINT MONO (-5545 -4740);
FORCEPROP 1 LAST TOLERANCE 5%
J 0
(-5505 -4625);
DISPLAY 0.510638 (-5505 -4625);
FORCEPROP 1 LAST VALUE 0
J 0
(-5505 -4575);
DISPLAY 0.510638 (-5505 -4575);
FORCEPROP 1 LAST WATTAGE 1/16W
J 0
(-5510 -4675);
DISPLAY 0.510638 (-5510 -4675);
FORCEPROP 1 LAST PACK_TYPE 0402LF
J 0
(-5510 -4825);
DISPLAY 0.510638 (-5510 -4825);
FORCEPROP 1 LAST MATERIAL EMPTY
J 0
(-5510 -4725);
DISPLAY 0.510638 (-5510 -4725);
PAINT RED (-5510 -4725);
FORCEPROP 2 LAST CDS_LIB pure_quanta
J 0
(-5550 -4650);
DISPLAY INVISIBLE (-5550 -4650);
FORCEPROP 2 LAST SEC_TYPE 0402LF
J 0
(-5500 -4425);
DISPLAY 1.021277 (-5500 -4425);
DISPLAY INVISIBLE (-5500 -4425);
FORCEPROP 1 LAST PART_NUMBER CS00002JB13
J 0
(-5510 -4775);
DISPLAY 0.510638 (-5510 -4775);
DISPLAY INVISIBLE (-5510 -4775);
FORCEPROP 1 LAST PATH I185
J 0
(-5500 -4475);
DISPLAY 0.978723 (-5500 -4475);
PAINT WHITE (-5500 -4475);
DISPLAY INVISIBLE (-5500 -4475);
FORCEADD UNIVERSAL_POWER..1
(-5550 -4350);
FORCEPROP 3 LASTPIN (-5550 -4400) SIG_NAME P3V3_AUX\g
J 0
(-5540 -4390);
DISPLAY 0.659574 (-5540 -4390);
PAINT MONO (-5540 -4390);
DISPLAY INVISIBLE (-5540 -4390);
FORCEPROP 1 LAST HDL_POWER P3V3_AUX
J 1
(-5550 -4300);
DISPLAY 0.872340 (-5550 -4300);
PAINT GREEN (-5550 -4300);
FORCEPROP 2 LAST CDS_LIB pure_quanta_power
J 0
(-5550 -4350);
DISPLAY INVISIBLE (-5550 -4350);
FORCEPROP 1 LAST PATH I186
J 0
(-5500 -4325);
DISPLAY 0.872340 (-5500 -4325);
PAINT AQUA (-5500 -4325);
DISPLAY INVISIBLE (-5500 -4325);
FORCEADD Q_RES..2
(975 -6625);
FORCEPROP 1 LAST LOCATION PR6557
J 0
(1020 -6500);
DISPLAY 0.787234 (1020 -6500);
FORCEPROP 2 LAST SEC 1
J 0
(1025 -6400);
DISPLAY 0.680851 (1025 -6400);
PAINT MONO (1025 -6400);
DISPLAY INVISIBLE (1025 -6400);
FORCEPROP 1 LASTPIN (975 -6525) $PN 1
J 0
(980 -6563);
DISPLAY 0.787234 (980 -6563);
PAINT MONO (980 -6563);
FORCEPROP 1 LASTPIN (975 -6725) $PN 2
J 0
(980 -6715);
DISPLAY 0.787234 (980 -6715);
PAINT MONO (980 -6715);
FORCEPROP 1 LAST TOLERANCE 1%
J 0
(1020 -6600);
DISPLAY 0.638298 (1020 -6600);
FORCEPROP 1 LAST PACK_TYPE 0603LF
J 0
(1015 -6800);
DISPLAY 0.638298 (1015 -6800);
FORCEPROP 1 LAST MATERIAL CHIP
J 0
(1015 -6700);
DISPLAY 0.638298 (1015 -6700);
FORCEPROP 1 LAST VALUE 499
J 0
(1020 -6550);
DISPLAY 0.638298 (1020 -6550);
FORCEPROP 1 LAST WATTAGE 1/10W
J 0
(1015 -6650);
DISPLAY 0.638298 (1015 -6650);
FORCEPROP 2 LAST CDS_LIB pure_quanta
J 0
(975 -6625);
DISPLAY INVISIBLE (975 -6625);
FORCEPROP 2 LAST SEC_TYPE 0603LF
J 0
(1025 -6400);
DISPLAY 1.021277 (1025 -6400);
DISPLAY INVISIBLE (1025 -6400);
FORCEPROP 1 LAST PART_NUMBER CS14993F901
J 0
(1015 -6750);
DISPLAY 0.638298 (1015 -6750);
DISPLAY INVISIBLE (1015 -6750);
FORCEPROP 1 LAST PATH I187
J 0
(1025 -6450);
DISPLAY 0.978723 (1025 -6450);
PAINT WHITE (1025 -6450);
DISPLAY INVISIBLE (1025 -6450);
FORCEADD UNIVERSAL_GND..1
(-6650 -7075);
FORCEPROP 3 LASTPIN (-6650 -7025) SIG_NAME GND\g
J 0
(-6640 -7015);
DISPLAY 0.659574 (-6640 -7015);
PAINT MONO (-6640 -7015);
DISPLAY INVISIBLE (-6640 -7015);
FORCEPROP 2 LAST CDS_LIB pure_quanta_power
J 0
(-6650 -7075);
DISPLAY INVISIBLE (-6650 -7075);
FORCEPROP 1 LAST HDL_POWER GND
J 1
(-6625 -7150);
DISPLAY 0.872340 (-6625 -7150);
PAINT GREEN (-6625 -7150);
DISPLAY INVISIBLE (-6625 -7150);
FORCEPROP 1 LAST PATH I188
J 0
(-6575 -7075);
DISPLAY 0.872340 (-6575 -7075);
PAINT AQUA (-6575 -7075);
DISPLAY INVISIBLE (-6575 -7075);
FORCEADD UNIVERSAL_GND..1
(-5850 -7250);
FORCEPROP 3 LASTPIN (-5850 -7200) SIG_NAME GND\g
J 0
(-5840 -7190);
DISPLAY 0.659574 (-5840 -7190);
PAINT MONO (-5840 -7190);
DISPLAY INVISIBLE (-5840 -7190);
FORCEPROP 2 LAST CDS_LIB pure_quanta_power
J 0
(-5850 -7250);
DISPLAY INVISIBLE (-5850 -7250);
FORCEPROP 1 LAST HDL_POWER GND
J 1
(-5825 -7325);
DISPLAY 0.872340 (-5825 -7325);
PAINT GREEN (-5825 -7325);
DISPLAY INVISIBLE (-5825 -7325);
FORCEPROP 1 LAST PATH I189
J 0
(-5775 -7250);
DISPLAY 0.872340 (-5775 -7250);
PAINT AQUA (-5775 -7250);
DISPLAY INVISIBLE (-5775 -7250);
FORCEADD UNIVERSAL_GND..1
(-5900 -6225);
FORCEPROP 3 LASTPIN (-5900 -6175) SIG_NAME GND\g
J 0
(-5890 -6165);
DISPLAY 0.659574 (-5890 -6165);
PAINT MONO (-5890 -6165);
DISPLAY INVISIBLE (-5890 -6165);
FORCEPROP 2 LAST CDS_LIB pure_quanta_power
J 0
(-5900 -6225);
DISPLAY INVISIBLE (-5900 -6225);
FORCEPROP 1 LAST HDL_POWER GND
J 1
(-5875 -6300);
DISPLAY 0.872340 (-5875 -6300);
PAINT GREEN (-5875 -6300);
DISPLAY INVISIBLE (-5875 -6300);
FORCEPROP 1 LAST PATH I190
J 0
(-5825 -6225);
DISPLAY 0.872340 (-5825 -6225);
PAINT AQUA (-5825 -6225);
DISPLAY INVISIBLE (-5825 -6225);
FORCEADD UNIVERSAL_GND..1
(-5200 -5750);
FORCEPROP 3 LASTPIN (-5200 -5700) SIG_NAME GND\g
J 0
(-5190 -5690);
DISPLAY 0.659574 (-5190 -5690);
PAINT MONO (-5190 -5690);
DISPLAY INVISIBLE (-5190 -5690);
FORCEPROP 2 LAST CDS_LIB pure_quanta_power
J 0
(-5200 -5750);
DISPLAY INVISIBLE (-5200 -5750);
FORCEPROP 1 LAST HDL_POWER GND
J 1
(-5175 -5825);
DISPLAY 0.872340 (-5175 -5825);
PAINT GREEN (-5175 -5825);
DISPLAY INVISIBLE (-5175 -5825);
FORCEPROP 1 LAST PATH I191
J 0
(-5125 -5750);
DISPLAY 0.872340 (-5125 -5750);
PAINT AQUA (-5125 -5750);
DISPLAY INVISIBLE (-5125 -5750);
FORCEADD UNIVERSAL_GND..1
(-3525 -7250);
FORCEPROP 3 LASTPIN (-3525 -7200) SIG_NAME GND\g
J 0
(-3515 -7190);
DISPLAY 0.659574 (-3515 -7190);
PAINT MONO (-3515 -7190);
DISPLAY INVISIBLE (-3515 -7190);
FORCEPROP 2 LAST CDS_LIB pure_quanta_power
J 0
(-3525 -7250);
DISPLAY INVISIBLE (-3525 -7250);
FORCEPROP 1 LAST HDL_POWER GND
J 1
(-3500 -7325);
DISPLAY 0.872340 (-3500 -7325);
PAINT GREEN (-3500 -7325);
DISPLAY INVISIBLE (-3500 -7325);
FORCEPROP 1 LAST PATH I192
J 0
(-3450 -7250);
DISPLAY 0.872340 (-3450 -7250);
PAINT AQUA (-3450 -7250);
DISPLAY INVISIBLE (-3450 -7250);
FORCEADD UNIVERSAL_GND..1
(600 -5950);
FORCEPROP 3 LASTPIN (600 -5900) SIG_NAME GND\g
J 0
(610 -5890);
DISPLAY 0.659574 (610 -5890);
PAINT MONO (610 -5890);
DISPLAY INVISIBLE (610 -5890);
FORCEPROP 2 LAST CDS_LIB pure_quanta_power
J 0
(600 -5950);
DISPLAY INVISIBLE (600 -5950);
FORCEPROP 1 LAST HDL_POWER GND
J 1
(625 -6025);
DISPLAY 0.872340 (625 -6025);
PAINT GREEN (625 -6025);
DISPLAY INVISIBLE (625 -6025);
FORCEPROP 1 LAST PATH I193
J 0
(675 -5950);
DISPLAY 0.872340 (675 -5950);
PAINT AQUA (675 -5950);
DISPLAY INVISIBLE (675 -5950);
FORCEADD UNIVERSAL_GND..1
(-1025 -5925);
FORCEPROP 3 LASTPIN (-1025 -5875) SIG_NAME GND\g
J 0
(-1015 -5865);
DISPLAY 0.659574 (-1015 -5865);
PAINT MONO (-1015 -5865);
DISPLAY INVISIBLE (-1015 -5865);
FORCEPROP 2 LAST CDS_LIB pure_quanta_power
J 0
(-1025 -5925);
DISPLAY INVISIBLE (-1025 -5925);
FORCEPROP 1 LAST HDL_POWER GND
J 1
(-1000 -6000);
DISPLAY 0.872340 (-1000 -6000);
PAINT GREEN (-1000 -6000);
DISPLAY INVISIBLE (-1000 -6000);
FORCEPROP 1 LAST PATH I194
J 0
(-950 -5925);
DISPLAY 0.872340 (-950 -5925);
PAINT AQUA (-950 -5925);
DISPLAY INVISIBLE (-950 -5925);
FORCEADD UNIVERSAL_GND..1
(-1500 -5925);
FORCEPROP 3 LASTPIN (-1500 -5875) SIG_NAME GND\g
J 0
(-1490 -5865);
DISPLAY 0.659574 (-1490 -5865);
PAINT MONO (-1490 -5865);
DISPLAY INVISIBLE (-1490 -5865);
FORCEPROP 2 LAST CDS_LIB pure_quanta_power
J 0
(-1500 -5925);
DISPLAY INVISIBLE (-1500 -5925);
FORCEPROP 1 LAST HDL_POWER GND
J 1
(-1475 -6000);
DISPLAY 0.872340 (-1475 -6000);
PAINT GREEN (-1475 -6000);
DISPLAY INVISIBLE (-1475 -6000);
FORCEPROP 1 LAST PATH I195
J 0
(-1425 -5925);
DISPLAY 0.872340 (-1425 -5925);
PAINT AQUA (-1425 -5925);
DISPLAY INVISIBLE (-1425 -5925);
FORCEADD UNIVERSAL_GND..1
(-2000 -5925);
FORCEPROP 3 LASTPIN (-2000 -5875) SIG_NAME GND\g
J 0
(-1990 -5865);
DISPLAY 0.659574 (-1990 -5865);
PAINT MONO (-1990 -5865);
DISPLAY INVISIBLE (-1990 -5865);
FORCEPROP 2 LAST CDS_LIB pure_quanta_power
J 0
(-2000 -5925);
DISPLAY INVISIBLE (-2000 -5925);
FORCEPROP 1 LAST HDL_POWER GND
J 1
(-1975 -6000);
DISPLAY 0.872340 (-1975 -6000);
PAINT GREEN (-1975 -6000);
DISPLAY INVISIBLE (-1975 -6000);
FORCEPROP 1 LAST PATH I196
J 0
(-1925 -5925);
DISPLAY 0.872340 (-1925 -5925);
PAINT AQUA (-1925 -5925);
DISPLAY INVISIBLE (-1925 -5925);
FORCEADD UNIVERSAL_GND..1
(-3000 -5925);
FORCEPROP 3 LASTPIN (-3000 -5875) SIG_NAME GND\g
J 0
(-2990 -5865);
DISPLAY 0.659574 (-2990 -5865);
PAINT MONO (-2990 -5865);
DISPLAY INVISIBLE (-2990 -5865);
FORCEPROP 2 LAST CDS_LIB pure_quanta_power
J 0
(-3000 -5925);
DISPLAY INVISIBLE (-3000 -5925);
FORCEPROP 1 LAST HDL_POWER GND
J 1
(-2975 -6000);
DISPLAY 0.872340 (-2975 -6000);
PAINT GREEN (-2975 -6000);
DISPLAY INVISIBLE (-2975 -6000);
FORCEPROP 1 LAST PATH I197
J 0
(-2925 -5925);
DISPLAY 0.872340 (-2925 -5925);
PAINT AQUA (-2925 -5925);
DISPLAY INVISIBLE (-2925 -5925);
FORCEADD UNIVERSAL_GND..1
(-2500 -5925);
FORCEPROP 3 LASTPIN (-2500 -5875) SIG_NAME GND\g
J 0
(-2490 -5865);
DISPLAY 0.659574 (-2490 -5865);
PAINT MONO (-2490 -5865);
DISPLAY INVISIBLE (-2490 -5865);
FORCEPROP 2 LAST CDS_LIB pure_quanta_power
J 0
(-2500 -5925);
DISPLAY INVISIBLE (-2500 -5925);
FORCEPROP 1 LAST HDL_POWER GND
J 1
(-2475 -6000);
DISPLAY 0.872340 (-2475 -6000);
PAINT GREEN (-2475 -6000);
DISPLAY INVISIBLE (-2475 -6000);
FORCEPROP 1 LAST PATH I198
J 0
(-2425 -5925);
DISPLAY 0.872340 (-2425 -5925);
PAINT AQUA (-2425 -5925);
DISPLAY INVISIBLE (-2425 -5925);
FORCEADD UNIVERSAL_GND..1
(975 -6925);
FORCEPROP 3 LASTPIN (975 -6875) SIG_NAME GND\g
J 0
(985 -6865);
DISPLAY 0.659574 (985 -6865);
PAINT MONO (985 -6865);
DISPLAY INVISIBLE (985 -6865);
FORCEPROP 2 LAST CDS_LIB pure_quanta_power
J 0
(975 -6925);
DISPLAY INVISIBLE (975 -6925);
FORCEPROP 1 LAST HDL_POWER GND
J 1
(1000 -7000);
DISPLAY 0.872340 (1000 -7000);
PAINT GREEN (1000 -7000);
DISPLAY INVISIBLE (1000 -7000);
FORCEPROP 1 LAST PATH I199
J 0
(1050 -6925);
DISPLAY 0.872340 (1050 -6925);
PAINT AQUA (1050 -6925);
DISPLAY INVISIBLE (1050 -6925);
FORCEADD Q_CAP..1
(-825 -6600);
FORCEPROP 1 LAST LOCATION PC6566_1
J 0
(-775 -6500);
DISPLAY 0.510638 (-775 -6500);
FORCEPROP 0 LAST $SEC 1
J 0
(-775 -6450);
DISPLAY 0.680851 (-775 -6450);
PAINT MONO (-775 -6450);
DISPLAY INVISIBLE (-775 -6450);
FORCEPROP 0 LAST CDS_SEC 1
J 0
(-775 -6450);
DISPLAY 1.021277 (-775 -6450);
DISPLAY INVISIBLE (-775 -6450);
FORCEPROP 1 LASTPIN (-825 -6500) $PN 1
J 0
(-815 -6520);
DISPLAY 0.787234 (-815 -6520);
PAINT MONO (-815 -6520);
FORCEPROP 1 LASTPIN (-825 -6700) $PN 2
J 0
(-815 -6720);
DISPLAY 0.787234 (-815 -6720);
PAINT MONO (-815 -6720);
FORCEPROP 1 LAST VALUE 22UF
J 0
(-775 -6550);
DISPLAY 0.510638 (-775 -6550);
FORCEPROP 1 LAST MATERIAL X6S
J 0
(-775 -6700);
DISPLAY 0.510638 (-775 -6700);
FORCEPROP 1 LAST PACK_TYPE C0805
J 0
(-775 -6750);
DISPLAY 0.510638 (-775 -6750);
FORCEPROP 1 LAST TOLERANCE 20%
J 0
(-775 -6650);
DISPLAY 0.510638 (-775 -6650);
FORCEPROP 1 LAST VOLTAGE 4V
J 0
(-775 -6600);
DISPLAY 0.510638 (-775 -6600);
FORCEPROP 2 LAST CDS_LIB pure_quanta
J 0
(-825 -6600);
DISPLAY INVISIBLE (-825 -6600);
FORCEPROP 1 LAST PART_NUMBER CH622KMEA03
J 0
(-775 -6800);
DISPLAY 0.510638 (-775 -6800);
DISPLAY INVISIBLE (-775 -6800);
FORCEPROP 1 LAST PATH I202
J 0
(-775 -6450);
DISPLAY 0.978723 (-775 -6450);
PAINT WHITE (-775 -6450);
DISPLAY INVISIBLE (-775 -6450);
FORCEADD Q_CAPP..1
(600 -5675);
FORCEPROP 1 LAST LOCATION PC6561
J 0
(650 -5575);
DISPLAY 0.787234 (650 -5575);
FORCEPROP 0 LAST $SEC 1
J 0
(650 -5525);
DISPLAY 0.680851 (650 -5525);
PAINT MONO (650 -5525);
DISPLAY INVISIBLE (650 -5525);
FORCEPROP 0 LAST CDS_SEC 1
J 0
(650 -5525);
DISPLAY 1.021277 (650 -5525);
DISPLAY INVISIBLE (650 -5525);
FORCEPROP 1 LASTPIN (600 -5575) $PN 1
J 0
(610 -5590);
DISPLAY 0.787234 (610 -5590);
PAINT MONO (610 -5590);
FORCEPROP 1 LASTPIN (600 -5775) $PN 2
J 0
(610 -5790);
DISPLAY 0.787234 (610 -5790);
PAINT MONO (610 -5790);
FORCEPROP 1 LAST MATERIAL OSCON
J 0
(650 -5775);
DISPLAY 0.510638 (650 -5775);
FORCEPROP 1 LAST VOLTAGE 16V
J 0
(650 -5725);
DISPLAY 0.510638 (650 -5725);
FORCEPROP 1 LAST PACK_TYPE SMLF
J 0
(650 -5825);
DISPLAY 0.510638 (650 -5825);
FORCEPROP 1 LAST TOLERANCE 20%
J 0
(650 -5675);
DISPLAY 0.510638 (650 -5675);
FORCEPROP 1 LAST VALUE 100UF
J 0
(650 -5625);
DISPLAY 0.510638 (650 -5625);
FORCEPROP 2 LAST CDS_LIB pure_quanta
J 0
(600 -5675);
DISPLAY INVISIBLE (600 -5675);
FORCEPROP 1 LAST PART_NUMBER CC71003MZ30
J 0
(650 -5875);
DISPLAY 0.510638 (650 -5875);
DISPLAY INVISIBLE (650 -5875);
FORCEPROP 1 LAST PATH I209
J 0
(650 -5525);
DISPLAY 0.978723 (650 -5525);
DISPLAY INVISIBLE (650 -5525);
FORCEADD Q_CAP..1
(-1025 -5650);
FORCEPROP 1 LAST LOCATION PC6558_1
J 0
(-975 -5550);
DISPLAY 0.787234 (-975 -5550);
FORCEPROP 0 LAST $SEC 1
J 0
(-975 -5500);
DISPLAY 0.680851 (-975 -5500);
PAINT MONO (-975 -5500);
DISPLAY INVISIBLE (-975 -5500);
FORCEPROP 0 LAST CDS_SEC 1
J 0
(-950 -5425);
DISPLAY 0.680851 (-950 -5425);
PAINT MONO (-950 -5425);
DISPLAY INVISIBLE (-950 -5425);
FORCEPROP 1 LASTPIN (-1025 -5550) $PN 1
J 0
(-1015 -5570);
DISPLAY 0.787234 (-1015 -5570);
PAINT MONO (-1015 -5570);
FORCEPROP 1 LASTPIN (-1025 -5750) $PN 2
J 0
(-1015 -5770);
DISPLAY 0.787234 (-1015 -5770);
PAINT MONO (-1015 -5770);
FORCEPROP 1 LAST PACK_TYPE C0805
J 0
(-975 -5850);
DISPLAY 0.638298 (-975 -5850);
FORCEPROP 1 LAST TOLERANCE 20%
J 0
(-975 -5700);
DISPLAY 0.638298 (-975 -5700);
FORCEPROP 1 LAST MATERIAL X6S
J 0
(-975 -5750);
DISPLAY 0.638298 (-975 -5750);
FORCEPROP 1 LAST VOLTAGE 16V
J 0
(-975 -5650);
DISPLAY 0.638298 (-975 -5650);
FORCEPROP 1 LAST VALUE 22UF
J 0
(-975 -5600);
DISPLAY 0.638298 (-975 -5600);
FORCEPROP 2 LAST CDS_LIB pure_quanta
J 0
(-1025 -5650);
DISPLAY INVISIBLE (-1025 -5650);
FORCEPROP 0 LAST REUSE_ID 41
J 0
(-975 -5450);
DISPLAY 0.680851 (-975 -5450);
DISPLAY INVISIBLE (-975 -5450);
FORCEPROP 2 LAST BOM_COST VR_DIMM 
J 0
(-975 -5500);
DISPLAY 0.680851 (-975 -5500);
DISPLAY INVISIBLE (-975 -5500);
FORCEPROP 1 LAST PART_NUMBER CH6223MEA01
J 0
(-975 -5800);
DISPLAY 0.638298 (-975 -5800);
DISPLAY INVISIBLE (-975 -5800);
FORCEPROP 1 LAST PATH I21
J 0
(-975 -5500);
DISPLAY 0.978723 (-975 -5500);
PAINT WHITE (-975 -5500);
DISPLAY INVISIBLE (-975 -5500);
FORCEADD Q_CAP..1
(-650 -5650);
FORCEPROP 1 LAST LOCATION PC6559_1
J 0
(-600 -5550);
DISPLAY 0.978723 (-600 -5550);
FORCEPROP 2 LAST SEC 1
J 0
(-600 -5450);
DISPLAY 0.680851 (-600 -5450);
PAINT MONO (-600 -5450);
DISPLAY INVISIBLE (-600 -5450);
FORCEPROP 1 LASTPIN (-650 -5550) $PN 1
J 0
(-640 -5570);
DISPLAY 0.787234 (-640 -5570);
PAINT MONO (-640 -5570);
FORCEPROP 1 LASTPIN (-650 -5750) $PN 2
J 0
(-640 -5770);
DISPLAY 0.787234 (-640 -5770);
PAINT MONO (-640 -5770);
FORCEPROP 1 LAST MATERIAL X6S
J 0
(-600 -5750);
DISPLAY 0.638298 (-600 -5750);
FORCEPROP 1 LAST VOLTAGE 16V
J 0
(-600 -5650);
DISPLAY 0.638298 (-600 -5650);
FORCEPROP 1 LAST TOLERANCE 20%
J 0
(-600 -5700);
DISPLAY 0.638298 (-600 -5700);
FORCEPROP 1 LAST PACK_TYPE C0805
J 0
(-600 -5850);
DISPLAY 0.638298 (-600 -5850);
FORCEPROP 1 LAST VALUE 22UF
J 0
(-600 -5600);
DISPLAY 0.638298 (-600 -5600);
FORCEPROP 2 LAST CDS_LIB pure_quanta
J 0
(-650 -5650);
DISPLAY INVISIBLE (-650 -5650);
FORCEPROP 2 LAST SEC_TYPE C0805
J 0
(-600 -5450);
DISPLAY 1.021277 (-600 -5450);
DISPLAY INVISIBLE (-600 -5450);
FORCEPROP 2 LAST BOM_COST VR_DIMM 
J 0
(-600 -5500);
DISPLAY 0.680851 (-600 -5500);
DISPLAY INVISIBLE (-600 -5500);
FORCEPROP 0 LAST REUSE_ID 41
J 0
(-600 -5450);
DISPLAY 0.680851 (-600 -5450);
DISPLAY INVISIBLE (-600 -5450);
FORCEPROP 1 LAST PART_NUMBER CH6223MEA01
J 0
(-600 -5800);
DISPLAY 0.638298 (-600 -5800);
DISPLAY INVISIBLE (-600 -5800);
FORCEPROP 1 LAST PATH I210
J 0
(-600 -5500);
DISPLAY 0.978723 (-600 -5500);
PAINT WHITE (-600 -5500);
DISPLAY INVISIBLE (-600 -5500);
FORCEADD UNIVERSAL_GND..1
(-650 -5925);
FORCEPROP 3 LASTPIN (-650 -5875) SIG_NAME GND\g
J 0
(-640 -5865);
DISPLAY 0.659574 (-640 -5865);
PAINT MONO (-640 -5865);
DISPLAY INVISIBLE (-640 -5865);
FORCEPROP 2 LAST CDS_LIB pure_quanta_power
J 0
(-650 -5925);
DISPLAY INVISIBLE (-650 -5925);
FORCEPROP 1 LAST HDL_POWER GND
J 1
(-625 -6000);
DISPLAY 0.872340 (-625 -6000);
PAINT GREEN (-625 -6000);
DISPLAY INVISIBLE (-625 -6000);
FORCEPROP 1 LAST PATH I211
J 0
(-575 -5925);
DISPLAY 0.872340 (-575 -5925);
PAINT AQUA (-575 -5925);
DISPLAY INVISIBLE (-575 -5925);
FORCEADD UNIVERSAL_GND..1
(-250 -5925);
FORCEPROP 3 LASTPIN (-250 -5875) SIG_NAME GND\g
J 0
(-240 -5865);
DISPLAY 0.659574 (-240 -5865);
PAINT MONO (-240 -5865);
DISPLAY INVISIBLE (-240 -5865);
FORCEPROP 2 LAST CDS_LIB pure_quanta_power
J 0
(-250 -5925);
DISPLAY INVISIBLE (-250 -5925);
FORCEPROP 1 LAST HDL_POWER GND
J 1
(-225 -6000);
DISPLAY 0.872340 (-225 -6000);
PAINT GREEN (-225 -6000);
DISPLAY INVISIBLE (-225 -6000);
FORCEPROP 1 LAST PATH I214
J 0
(-175 -5925);
DISPLAY 0.872340 (-175 -5925);
PAINT AQUA (-175 -5925);
DISPLAY INVISIBLE (-175 -5925);
FORCEADD UNIVERSAL_GND..1
(200 -5925);
FORCEPROP 3 LASTPIN (200 -5875) SIG_NAME GND\g
J 0
(210 -5865);
DISPLAY 0.659574 (210 -5865);
PAINT MONO (210 -5865);
DISPLAY INVISIBLE (210 -5865);
FORCEPROP 2 LAST CDS_LIB pure_quanta_power
J 0
(200 -5925);
DISPLAY INVISIBLE (200 -5925);
FORCEPROP 1 LAST HDL_POWER GND
J 1
(225 -6000);
DISPLAY 0.872340 (225 -6000);
PAINT GREEN (225 -6000);
DISPLAY INVISIBLE (225 -6000);
FORCEPROP 1 LAST PATH I215
J 0
(275 -5925);
DISPLAY 0.872340 (275 -5925);
PAINT AQUA (275 -5925);
DISPLAY INVISIBLE (275 -5925);
FORCEADD Q_CAP..1
(200 -5700);
FORCEPROP 1 LAST LOCATION PC6816
J 0
(250 -5600);
DISPLAY 0.978723 (250 -5600);
FORCEPROP 2 LAST SEC 1
J 0
(250 -5500);
DISPLAY 0.680851 (250 -5500);
PAINT MONO (250 -5500);
DISPLAY INVISIBLE (250 -5500);
FORCEPROP 1 LASTPIN (200 -5600) $PN 1
J 0
(210 -5620);
DISPLAY 0.787234 (210 -5620);
PAINT MONO (210 -5620);
FORCEPROP 1 LASTPIN (200 -5800) $PN 2
J 0
(210 -5820);
DISPLAY 0.787234 (210 -5820);
PAINT MONO (210 -5820);
FORCEPROP 1 LAST VALUE 22UF
J 0
(250 -5650);
DISPLAY 0.510638 (250 -5650);
FORCEPROP 1 LAST VOLTAGE 16V
J 0
(250 -5700);
DISPLAY 0.510638 (250 -5700);
FORCEPROP 1 LAST TOLERANCE 20%
J 0
(250 -5750);
DISPLAY 0.510638 (250 -5750);
FORCEPROP 1 LAST MATERIAL X6S
J 0
(250 -5800);
DISPLAY 0.510638 (250 -5800);
FORCEPROP 1 LAST PACK_TYPE C0805
J 0
(250 -5900);
DISPLAY 0.510638 (250 -5900);
FORCEPROP 2 LAST CDS_LIB pure_quanta
J 0
(200 -5700);
DISPLAY INVISIBLE (200 -5700);
FORCEPROP 2 LAST SEC_TYPE C0805
J 0
(250 -5500);
DISPLAY 1.021277 (250 -5500);
DISPLAY INVISIBLE (250 -5500);
FORCEPROP 1 LAST PART_NUMBER CH6223MEA01
J 0
(250 -5850);
DISPLAY 0.510638 (250 -5850);
DISPLAY INVISIBLE (250 -5850);
FORCEPROP 1 LAST PATH I216
J 0
(250 -5550);
DISPLAY 0.978723 (250 -5550);
PAINT WHITE (250 -5550);
DISPLAY INVISIBLE (250 -5550);
FORCEADD Q_CAP..1
(-250 -5700);
FORCEPROP 1 LAST LOCATION PC6560
J 0
(-200 -5600);
DISPLAY 0.978723 (-200 -5600);
FORCEPROP 2 LAST SEC 1
J 0
(-200 -5500);
DISPLAY 0.680851 (-200 -5500);
PAINT MONO (-200 -5500);
DISPLAY INVISIBLE (-200 -5500);
FORCEPROP 1 LASTPIN (-250 -5600) $PN 1
J 0
(-240 -5620);
DISPLAY 0.787234 (-240 -5620);
PAINT MONO (-240 -5620);
FORCEPROP 1 LASTPIN (-250 -5800) $PN 2
J 0
(-240 -5820);
DISPLAY 0.787234 (-240 -5820);
PAINT MONO (-240 -5820);
FORCEPROP 1 LAST TOLERANCE 20%
J 0
(-200 -5750);
DISPLAY 0.510638 (-200 -5750);
FORCEPROP 1 LAST MATERIAL X6S
J 0
(-200 -5800);
DISPLAY 0.510638 (-200 -5800);
FORCEPROP 1 LAST VOLTAGE 16V
J 0
(-200 -5700);
DISPLAY 0.510638 (-200 -5700);
FORCEPROP 1 LAST PACK_TYPE C0805
J 0
(-200 -5900);
DISPLAY 0.510638 (-200 -5900);
FORCEPROP 1 LAST VALUE 22UF
J 0
(-200 -5650);
DISPLAY 0.510638 (-200 -5650);
FORCEPROP 2 LAST CDS_LIB pure_quanta
J 0
(-250 -5700);
DISPLAY INVISIBLE (-250 -5700);
FORCEPROP 2 LAST SEC_TYPE C0805
J 0
(-200 -5500);
DISPLAY 1.021277 (-200 -5500);
DISPLAY INVISIBLE (-200 -5500);
FORCEPROP 1 LAST PART_NUMBER CH6223MEA01
J 0
(-200 -5850);
DISPLAY 0.510638 (-200 -5850);
DISPLAY INVISIBLE (-200 -5850);
FORCEPROP 1 LAST PATH I217
J 0
(-200 -5550);
DISPLAY 0.978723 (-200 -5550);
PAINT WHITE (-200 -5550);
DISPLAY INVISIBLE (-200 -5550);
FORCEADD Q_RES..2
(-5850 -7000);
FORCEPROP 1 LAST LOCATION PR6553
J 0
(-5805 -6875);
DISPLAY 0.978723 (-5805 -6875);
FORCEPROP 2 LAST SEC 1
J 0
(-5800 -6775);
DISPLAY 0.680851 (-5800 -6775);
PAINT MONO (-5800 -6775);
DISPLAY INVISIBLE (-5800 -6775);
FORCEPROP 1 LASTPIN (-5850 -6900) $PN 1
J 0
(-5845 -6938);
DISPLAY 0.787234 (-5845 -6938);
PAINT MONO (-5845 -6938);
FORCEPROP 1 LASTPIN (-5850 -7100) $PN 2
J 0
(-5845 -7090);
DISPLAY 0.787234 (-5845 -7090);
PAINT MONO (-5845 -7090);
FORCEPROP 1 LAST MATERIAL EMPTY
J 0
(-5810 -7075);
DISPLAY 0.510638 (-5810 -7075);
FORCEPROP 1 LAST VALUE 8.87K
J 0
(-5805 -6925);
DISPLAY 0.510638 (-5805 -6925);
FORCEPROP 1 LAST TOLERANCE 1%
J 0
(-5805 -6975);
DISPLAY 0.510638 (-5805 -6975);
FORCEPROP 1 LAST PACK_TYPE 0402LF
J 0
(-5810 -7175);
DISPLAY 0.510638 (-5810 -7175);
FORCEPROP 1 LAST WATTAGE 1/16W
J 0
(-5810 -7025);
DISPLAY 0.510638 (-5810 -7025);
FORCEPROP 2 LAST CDS_LIB pure_quanta
J 0
(-5850 -7000);
DISPLAY INVISIBLE (-5850 -7000);
FORCEPROP 2 LAST SEC_TYPE 0402LF
J 0
(-5800 -6775);
DISPLAY 1.021277 (-5800 -6775);
DISPLAY INVISIBLE (-5800 -6775);
FORCEPROP 1 LAST PART_NUMBER CS28872FB01
J 0
(-5810 -7125);
DISPLAY 0.510638 (-5810 -7125);
DISPLAY INVISIBLE (-5810 -7125);
FORCEPROP 1 LAST PATH I220
J 0
(-5800 -6825);
DISPLAY 0.978723 (-5800 -6825);
PAINT WHITE (-5800 -6825);
DISPLAY INVISIBLE (-5800 -6825);
FORCEADD Q_RES..1
(-2500 -6100);
FORCEPROP 1 LAST LOCATION PR6554
J 0
(-2725 -6100);
DISPLAY 0.638298 (-2725 -6100);
FORCEPROP 2 LAST SEC 1
J 0
(-2550 -5900);
DISPLAY 0.680851 (-2550 -5900);
PAINT MONO (-2550 -5900);
DISPLAY INVISIBLE (-2550 -5900);
FORCEPROP 1 LASTPIN (-2600 -6100) $PN 1
J 0
(-2588 -6088);
DISPLAY 0.787234 (-2588 -6088);
PAINT MONO (-2588 -6088);
FORCEPROP 1 LASTPIN (-2400 -6100) $PN 2
J 0
(-2438 -6088);
DISPLAY 0.787234 (-2438 -6088);
PAINT MONO (-2438 -6088);
FORCEPROP 1 LAST MATERIAL CHIP
J 0
(-2650 -5975);
DISPLAY 0.510638 (-2650 -5975);
FORCEPROP 1 LAST WATTAGE 1/16W
J 2
(-2400 -5975);
DISPLAY 0.510638 (-2400 -5975);
FORCEPROP 1 LAST VALUE 5.6
J 2
(-2325 -6100);
DISPLAY 0.510638 (-2325 -6100);
FORCEPROP 1 LAST TOLERANCE 1%
J 0
(-2300 -6100);
DISPLAY 0.510638 (-2300 -6100);
FORCEPROP 1 LAST PACK_TYPE 0402LF
J 0
(-2375 -5975);
DISPLAY 0.510638 (-2375 -5975);
FORCEPROP 2 LAST CDS_LIB pure_quanta
J 0
(-2500 -6100);
DISPLAY INVISIBLE (-2500 -6100);
FORCEPROP 2 LAST SEC_TYPE 0402LF
J 0
(-2550 -5900);
DISPLAY 1.021277 (-2550 -5900);
DISPLAY INVISIBLE (-2550 -5900);
FORCEPROP 1 LAST PART_NUMBER CS-5602FB01
J 0
(-2650 -6025);
DISPLAY 0.510638 (-2650 -6025);
DISPLAY INVISIBLE (-2650 -6025);
FORCEPROP 1 LAST PATH I221
J 0
(-2550 -5950);
DISPLAY 0.978723 (-2550 -5950);
PAINT WHITE (-2550 -5950);
DISPLAY INVISIBLE (-2550 -5950);
FORCEADD Q_CAPP..1
(625 -6600);
FORCEPROP 1 LAST LOCATION PC6572
J 0
(675 -6500);
DISPLAY 0.638298 (675 -6500);
FORCEPROP 0 LAST $SEC 1
J 0
(675 -6450);
DISPLAY 0.680851 (675 -6450);
PAINT MONO (675 -6450);
DISPLAY INVISIBLE (675 -6450);
FORCEPROP 0 LAST CDS_SEC 1
J 0
(675 -6450);
DISPLAY 1.021277 (675 -6450);
DISPLAY INVISIBLE (675 -6450);
FORCEPROP 1 LASTPIN (625 -6500) $PN 1
J 0
(635 -6515);
DISPLAY 0.787234 (635 -6515);
PAINT MONO (635 -6515);
FORCEPROP 1 LASTPIN (625 -6700) $PN 2
J 0
(635 -6715);
DISPLAY 0.787234 (635 -6715);
PAINT MONO (635 -6715);
FORCEPROP 1 LAST MATERIAL ALUM
J 0
(675 -6700);
DISPLAY 0.510638 (675 -6700);
FORCEPROP 1 LAST VALUE 390UF
J 0
(675 -6550);
DISPLAY 0.510638 (675 -6550);
FORCEPROP 1 LAST PACK_TYPE SMLF
J 0
(675 -6750);
DISPLAY 0.510638 (675 -6750);
FORCEPROP 1 LAST VOLTAGE 2.5V
J 0
(675 -6650);
DISPLAY 0.510638 (675 -6650);
FORCEPROP 1 LAST TOLERANCE 20%
J 0
(675 -6600);
DISPLAY 0.510638 (675 -6600);
FORCEPROP 2 LAST CDS_LIB pure_quanta
J 0
(625 -6600);
DISPLAY INVISIBLE (625 -6600);
FORCEPROP 1 LAST PART_NUMBER CC7390JMZ13
J 0
(675 -6800);
DISPLAY 0.510638 (675 -6800);
DISPLAY INVISIBLE (675 -6800);
FORCEPROP 1 LAST PATH I222
J 0
(675 -6450);
DISPLAY 0.978723 (675 -6450);
DISPLAY INVISIBLE (675 -6450);
FORCEADD Q_CAP..1
(-600 -6600);
FORCEPROP 1 LAST LOCATION PC6567_1
J 0
(-575 -6500);
DISPLAY 0.510638 (-575 -6500);
FORCEPROP 0 LAST $SEC 1
J 0
(-575 -6475);
DISPLAY 0.680851 (-575 -6475);
PAINT MONO (-575 -6475);
DISPLAY INVISIBLE (-575 -6475);
FORCEPROP 0 LAST CDS_SEC 1
J 0
(-575 -6475);
DISPLAY 0.680851 (-575 -6475);
DISPLAY INVISIBLE (-575 -6475);
FORCEPROP 1 LASTPIN (-600 -6500) $PN 1
J 0
(-590 -6520);
DISPLAY 0.787234 (-590 -6520);
PAINT MONO (-590 -6520);
FORCEPROP 1 LASTPIN (-600 -6700) $PN 2
J 0
(-590 -6720);
DISPLAY 0.787234 (-590 -6720);
PAINT MONO (-590 -6720);
FORCEPROP 1 LAST PACK_TYPE C0805
J 0
(-550 -6750);
DISPLAY 0.510638 (-550 -6750);
FORCEPROP 1 LAST MATERIAL X6S
J 0
(-550 -6700);
DISPLAY 0.510638 (-550 -6700);
FORCEPROP 1 LAST TOLERANCE 20%
J 0
(-550 -6650);
DISPLAY 0.510638 (-550 -6650);
FORCEPROP 1 LAST VALUE 22UF
J 0
(-550 -6550);
DISPLAY 0.510638 (-550 -6550);
FORCEPROP 1 LAST VOLTAGE 4V
J 0
(-550 -6600);
DISPLAY 0.510638 (-550 -6600);
FORCEPROP 2 LAST CDS_LIB pure_quanta
J 0
(-600 -6600);
DISPLAY INVISIBLE (-600 -6600);
FORCEPROP 1 LAST PART_NUMBER CH622KMEA03
J 0
(-550 -6750);
DISPLAY 0.510638 (-550 -6750);
DISPLAY INVISIBLE (-550 -6750);
FORCEPROP 1 LAST PATH I223
J 0
(-550 -6450);
DISPLAY 0.978723 (-550 -6450);
PAINT WHITE (-550 -6450);
DISPLAY INVISIBLE (-550 -6450);
FORCEADD Q_CAPP..1
(-375 -6600);
FORCEPROP 1 LAST LOCATION PC6568
J 0
(-325 -6500);
DISPLAY 0.638298 (-325 -6500);
FORCEPROP 0 LAST $SEC 1
J 0
(-325 -6450);
DISPLAY 0.680851 (-325 -6450);
PAINT MONO (-325 -6450);
DISPLAY INVISIBLE (-325 -6450);
FORCEPROP 0 LAST CDS_SEC 1
J 0
(-325 -6450);
DISPLAY 0.680851 (-325 -6450);
DISPLAY INVISIBLE (-325 -6450);
FORCEPROP 1 LASTPIN (-375 -6500) $PN 1
J 0
(-365 -6515);
DISPLAY 0.787234 (-365 -6515);
PAINT MONO (-365 -6515);
FORCEPROP 1 LASTPIN (-375 -6700) $PN 2
J 0
(-365 -6715);
DISPLAY 0.787234 (-365 -6715);
PAINT MONO (-365 -6715);
FORCEPROP 1 LAST PACK_TYPE SMLF
J 0
(-325 -6750);
DISPLAY 0.510638 (-325 -6750);
FORCEPROP 1 LAST VALUE 470UF
J 0
(-325 -6550);
DISPLAY 0.510638 (-325 -6550);
FORCEPROP 1 LAST TOLERANCE 20%
J 0
(-325 -6600);
DISPLAY 0.510638 (-325 -6600);
FORCEPROP 1 LAST VOLTAGE 2.5V
J 0
(-325 -6650);
DISPLAY 0.510638 (-325 -6650);
FORCEPROP 1 LAST MATERIAL SPCAP
J 0
(-325 -6700);
DISPLAY 0.510638 (-325 -6700);
FORCEPROP 2 LAST CDS_LIB pure_quanta
J 0
(-375 -6600);
DISPLAY INVISIBLE (-375 -6600);
FORCEPROP 1 LAST PART_NUMBER CH747LM8818
J 0
(-325 -6800);
DISPLAY 0.510638 (-325 -6800);
DISPLAY INVISIBLE (-325 -6800);
FORCEPROP 1 LAST PATH I224
J 0
(-325 -6450);
DISPLAY 0.978723 (-325 -6450);
DISPLAY INVISIBLE (-325 -6450);
FORCEADD Q_CAPP..1
(-150 -6600);
FORCEPROP 1 LAST LOCATION PC6569
J 0
(-100 -6500);
DISPLAY 0.638298 (-100 -6500);
FORCEPROP 0 LAST $SEC 1
J 0
(-100 -6450);
DISPLAY 0.680851 (-100 -6450);
PAINT MONO (-100 -6450);
DISPLAY INVISIBLE (-100 -6450);
FORCEPROP 0 LAST CDS_SEC 1
J 0
(-100 -6450);
DISPLAY 0.680851 (-100 -6450);
DISPLAY INVISIBLE (-100 -6450);
FORCEPROP 1 LASTPIN (-150 -6500) $PN 1
J 0
(-140 -6515);
DISPLAY 0.787234 (-140 -6515);
PAINT MONO (-140 -6515);
FORCEPROP 1 LASTPIN (-150 -6700) $PN 2
J 0
(-140 -6715);
DISPLAY 0.787234 (-140 -6715);
PAINT MONO (-140 -6715);
FORCEPROP 1 LAST TOLERANCE 20%
J 0
(-100 -6600);
DISPLAY 0.510638 (-100 -6600);
FORCEPROP 1 LAST VALUE 470UF
J 0
(-100 -6550);
DISPLAY 0.510638 (-100 -6550);
FORCEPROP 1 LAST PACK_TYPE SMLF
J 0
(-100 -6750);
DISPLAY 0.510638 (-100 -6750);
FORCEPROP 1 LAST VOLTAGE 2.5V
J 0
(-100 -6650);
DISPLAY 0.510638 (-100 -6650);
FORCEPROP 1 LAST MATERIAL SPCAP
J 0
(-100 -6700);
DISPLAY 0.510638 (-100 -6700);
FORCEPROP 2 LAST CDS_LIB pure_quanta
J 0
(-150 -6600);
DISPLAY INVISIBLE (-150 -6600);
FORCEPROP 1 LAST PART_NUMBER CH747LM8818
J 0
(-100 -6800);
DISPLAY 0.510638 (-100 -6800);
DISPLAY INVISIBLE (-100 -6800);
FORCEPROP 1 LAST PATH I225
J 0
(-100 -6450);
DISPLAY 0.978723 (-100 -6450);
DISPLAY INVISIBLE (-100 -6450);
FORCEADD Q_CAPP..1
(50 -6600);
FORCEPROP 1 LAST LOCATION PC6570
J 0
(100 -6500);
DISPLAY 0.638298 (100 -6500);
FORCEPROP 0 LAST $SEC 1
J 0
(100 -6450);
DISPLAY 0.680851 (100 -6450);
PAINT MONO (100 -6450);
DISPLAY INVISIBLE (100 -6450);
FORCEPROP 0 LAST CDS_SEC 1
J 0
(100 -6450);
DISPLAY 0.680851 (100 -6450);
DISPLAY INVISIBLE (100 -6450);
FORCEPROP 1 LASTPIN (50 -6500) $PN 1
J 0
(60 -6515);
DISPLAY 0.787234 (60 -6515);
PAINT MONO (60 -6515);
FORCEPROP 1 LASTPIN (50 -6700) $PN 2
J 0
(60 -6715);
DISPLAY 0.787234 (60 -6715);
PAINT MONO (60 -6715);
FORCEPROP 1 LAST TOLERANCE 20%
J 0
(100 -6600);
DISPLAY 0.510638 (100 -6600);
FORCEPROP 1 LAST PACK_TYPE SMLF
J 0
(100 -6750);
DISPLAY 0.510638 (100 -6750);
FORCEPROP 1 LAST VALUE 470UF
J 0
(100 -6550);
DISPLAY 0.510638 (100 -6550);
FORCEPROP 1 LAST VOLTAGE 2.5V
J 0
(100 -6650);
DISPLAY 0.510638 (100 -6650);
FORCEPROP 1 LAST MATERIAL SPCAP
J 0
(100 -6700);
DISPLAY 0.510638 (100 -6700);
FORCEPROP 2 LAST CDS_LIB pure_quanta
J 0
(50 -6600);
DISPLAY INVISIBLE (50 -6600);
FORCEPROP 1 LAST PART_NUMBER CH747LM8818
J 0
(100 -6800);
DISPLAY 0.510638 (100 -6800);
DISPLAY INVISIBLE (100 -6800);
FORCEPROP 1 LAST PATH I226
J 0
(100 -6450);
DISPLAY 0.978723 (100 -6450);
DISPLAY INVISIBLE (100 -6450);
FORCEADD Q_CAPP..1
(375 -6600);
FORCEPROP 1 LAST LOCATION PC6571
J 0
(425 -6500);
DISPLAY 0.638298 (425 -6500);
FORCEPROP 0 LAST $SEC 1
J 0
(425 -6450);
DISPLAY 0.680851 (425 -6450);
PAINT MONO (425 -6450);
DISPLAY INVISIBLE (425 -6450);
FORCEPROP 0 LAST CDS_SEC 1
J 0
(425 -6450);
DISPLAY 0.680851 (425 -6450);
DISPLAY INVISIBLE (425 -6450);
FORCEPROP 1 LASTPIN (375 -6500) $PN 1
J 0
(385 -6515);
DISPLAY 0.787234 (385 -6515);
PAINT MONO (385 -6515);
FORCEPROP 1 LASTPIN (375 -6700) $PN 2
J 0
(385 -6715);
DISPLAY 0.787234 (385 -6715);
PAINT MONO (385 -6715);
FORCEPROP 1 LAST TOLERANCE 20%
J 0
(425 -6600);
DISPLAY 0.510638 (425 -6600);
FORCEPROP 1 LAST MATERIAL ALUM
J 0
(425 -6700);
DISPLAY 0.510638 (425 -6700);
FORCEPROP 1 LAST PACK_TYPE SMLF
J 0
(425 -6750);
DISPLAY 0.510638 (425 -6750);
FORCEPROP 1 LAST VALUE 390UF
J 0
(425 -6550);
DISPLAY 0.510638 (425 -6550);
FORCEPROP 1 LAST VOLTAGE 2.5V
J 0
(425 -6650);
DISPLAY 0.510638 (425 -6650);
FORCEPROP 2 LAST CDS_LIB pure_quanta
J 0
(375 -6600);
DISPLAY INVISIBLE (375 -6600);
FORCEPROP 1 LAST PART_NUMBER CC7390JMZ13
J 0
(425 -6800);
DISPLAY 0.510638 (425 -6800);
DISPLAY INVISIBLE (425 -6800);
FORCEPROP 1 LAST PATH I227
J 0
(425 -6450);
DISPLAY 0.978723 (425 -6450);
DISPLAY INVISIBLE (425 -6450);
FORCEADD VCC15..1
(550 -5250);
FORCEPROP 3 LASTPIN (550 -5300) SIG_NAME SW_P12V_AUX_P0V9_RETIMER_CPU0_FLT\g
J 0
(560 -5290);
DISPLAY 0.659574 (560 -5290);
PAINT MONO (560 -5290);
DISPLAY INVISIBLE (560 -5290);
FORCEPROP 1 LAST HDL_POWER SW_P12V_AUX_P0V9_RETIMER_CPU0_FLT
J 1
(450 -5175);
DISPLAY 0.617021 (450 -5175);
PAINT GREEN (450 -5175);
FORCEPROP 2 LAST CDS_LIB pure_quanta_power
J 0
(550 -5250);
PAINT MONO (550 -5250);
DISPLAY INVISIBLE (550 -5250);
FORCEPROP 2 LAST BOM_COST VR_DIMM 
J 0
(450 -5125);
DISPLAY 0.680851 (450 -5125);
DISPLAY INVISIBLE (450 -5125);
FORCEPROP 1 LAST PATH I23
J 0
(600 -5225);
DISPLAY 0.872340 (600 -5225);
PAINT AQUA (600 -5225);
DISPLAY INVISIBLE (600 -5225);
FORCEADD VCC15..1
(675 -8150);
FORCEPROP 3 LASTPIN (675 -8200) SIG_NAME SW_P12V_AUX_P0V9_RETIMER_CPU0_FLT\g
J 0
(685 -8190);
DISPLAY 0.659574 (685 -8190);
PAINT MONO (685 -8190);
DISPLAY INVISIBLE (685 -8190);
FORCEPROP 1 LAST HDL_POWER SW_P12V_AUX_P0V9_RETIMER_CPU0_FLT
J 1
(575 -8075);
DISPLAY 0.617021 (575 -8075);
PAINT GREEN (575 -8075);
FORCEPROP 2 LAST CDS_LIB pure_quanta_power
J 0
(675 -8150);
DISPLAY INVISIBLE (675 -8150);
FORCEPROP 2 LAST BOM_COST VR_DIMM 
J 0
(575 -8025);
DISPLAY 0.680851 (575 -8025);
DISPLAY INVISIBLE (575 -8025);
FORCEPROP 1 LAST PATH I230
J 0
(725 -8125);
DISPLAY 0.872340 (725 -8125);
PAINT AQUA (725 -8125);
DISPLAY INVISIBLE (725 -8125);
FORCEADD Q_CAPP..1
(725 -8575);
FORCEPROP 1 LAST LOCATION PC6810
J 0
(775 -8475);
DISPLAY 0.787234 (775 -8475);
FORCEPROP 0 LAST $SEC 1
J 0
(775 -8425);
DISPLAY 0.680851 (775 -8425);
PAINT MONO (775 -8425);
DISPLAY INVISIBLE (775 -8425);
FORCEPROP 0 LAST CDS_SEC 1
J 0
(775 -8425);
DISPLAY 0.680851 (775 -8425);
DISPLAY INVISIBLE (775 -8425);
FORCEPROP 1 LASTPIN (725 -8475) $PN 1
J 0
(735 -8490);
DISPLAY 0.787234 (735 -8490);
PAINT MONO (735 -8490);
FORCEPROP 1 LASTPIN (725 -8675) $PN 2
J 0
(735 -8690);
DISPLAY 0.787234 (735 -8690);
PAINT MONO (735 -8690);
FORCEPROP 1 LAST VALUE 100UF
J 0
(775 -8525);
DISPLAY 0.510638 (775 -8525);
FORCEPROP 1 LAST VOLTAGE 16V
J 0
(775 -8625);
DISPLAY 0.510638 (775 -8625);
FORCEPROP 1 LAST TOLERANCE 20%
J 0
(775 -8575);
DISPLAY 0.510638 (775 -8575);
FORCEPROP 1 LAST MATERIAL OSCON
J 0
(775 -8675);
DISPLAY 0.510638 (775 -8675);
FORCEPROP 1 LAST PACK_TYPE SMLF
J 0
(775 -8725);
DISPLAY 0.510638 (775 -8725);
FORCEPROP 2 LAST CDS_LIB pure_quanta
J 0
(725 -8575);
DISPLAY INVISIBLE (725 -8575);
FORCEPROP 1 LAST PART_NUMBER CC71003MZ30
J 0
(775 -8775);
DISPLAY 0.510638 (775 -8775);
DISPLAY INVISIBLE (775 -8775);
FORCEPROP 1 LAST PATH I231
J 0
(775 -8425);
DISPLAY 0.978723 (775 -8425);
DISPLAY INVISIBLE (775 -8425);
FORCEADD Q_CAP..1
(325 -8600);
FORCEPROP 1 LAST LOCATION PC6817
J 0
(375 -8500);
DISPLAY 0.978723 (375 -8500);
FORCEPROP 0 LAST $SEC 1
J 0
(375 -8450);
DISPLAY 0.680851 (375 -8450);
PAINT MONO (375 -8450);
DISPLAY INVISIBLE (375 -8450);
FORCEPROP 0 LAST CDS_SEC 1
J 0
(375 -8450);
DISPLAY 0.680851 (375 -8450);
DISPLAY INVISIBLE (375 -8450);
FORCEPROP 1 LASTPIN (325 -8500) $PN 1
J 0
(335 -8520);
DISPLAY 0.787234 (335 -8520);
PAINT MONO (335 -8520);
FORCEPROP 1 LASTPIN (325 -8700) $PN 2
J 0
(335 -8720);
DISPLAY 0.787234 (335 -8720);
PAINT MONO (335 -8720);
FORCEPROP 1 LAST VOLTAGE 16V
J 0
(375 -8600);
DISPLAY 0.510638 (375 -8600);
FORCEPROP 1 LAST TOLERANCE 20%
J 0
(375 -8650);
DISPLAY 0.510638 (375 -8650);
FORCEPROP 1 LAST VALUE 22UF
J 0
(375 -8550);
DISPLAY 0.510638 (375 -8550);
FORCEPROP 1 LAST PACK_TYPE C0805
J 0
(375 -8800);
DISPLAY 0.510638 (375 -8800);
FORCEPROP 1 LAST MATERIAL X6S
J 0
(375 -8700);
DISPLAY 0.510638 (375 -8700);
FORCEPROP 2 LAST CDS_LIB pure_quanta
J 0
(325 -8600);
DISPLAY INVISIBLE (325 -8600);
FORCEPROP 1 LAST PART_NUMBER CH6223MEA01
J 0
(375 -8750);
DISPLAY 0.510638 (375 -8750);
DISPLAY INVISIBLE (375 -8750);
FORCEPROP 1 LAST PATH I232
J 0
(375 -8450);
DISPLAY 0.978723 (375 -8450);
PAINT WHITE (375 -8450);
DISPLAY INVISIBLE (375 -8450);
FORCEADD VCC15..1
(1725 -9025);
FORCEPROP 3 LASTPIN (1725 -9075) SIG_NAME P0V9_CPU0_RT_2D\g
J 0
(1735 -9065);
DISPLAY 0.659574 (1735 -9065);
PAINT MONO (1735 -9065);
DISPLAY INVISIBLE (1735 -9065);
FORCEPROP 1 LAST HDL_POWER P0V9_CPU0_RT_2D
J 1
(1725 -8975);
DISPLAY 0.617021 (1725 -8975);
PAINT GREEN (1725 -8975);
FORCEPROP 2 LAST CDS_LIB pure_quanta_power
J 0
(1725 -9025);
DISPLAY INVISIBLE (1725 -9025);
FORCEPROP 2 LAST BOM_COST VR_DIMM 
J 0
(1725 -8925);
DISPLAY 0.680851 (1725 -8925);
DISPLAY INVISIBLE (1725 -8925);
FORCEPROP 1 LAST PATH I233
J 0
(1775 -9000);
DISPLAY 0.872340 (1775 -9000);
PAINT AQUA (1775 -9000);
DISPLAY INVISIBLE (1775 -9000);
FORCEADD UNIVERSAL_GND..1
(725 -8850);
FORCEPROP 3 LASTPIN (725 -8800) SIG_NAME GND\g
J 0
(735 -8790);
DISPLAY 0.659574 (735 -8790);
PAINT MONO (735 -8790);
DISPLAY INVISIBLE (735 -8790);
FORCEPROP 2 LAST CDS_LIB pure_quanta_power
J 0
(725 -8850);
DISPLAY INVISIBLE (725 -8850);
FORCEPROP 1 LAST HDL_POWER GND
J 1
(750 -8925);
DISPLAY 0.872340 (750 -8925);
PAINT GREEN (750 -8925);
DISPLAY INVISIBLE (750 -8925);
FORCEPROP 1 LAST PATH I234
J 0
(800 -8850);
DISPLAY 0.872340 (800 -8850);
PAINT AQUA (800 -8850);
DISPLAY INVISIBLE (800 -8850);
FORCEADD Q_CAPP..1
(750 -9500);
FORCEPROP 1 LAST LOCATION PC6574
J 0
(800 -9400);
DISPLAY 0.638298 (800 -9400);
FORCEPROP 0 LAST $SEC 1
J 0
(800 -9350);
DISPLAY 0.680851 (800 -9350);
PAINT MONO (800 -9350);
DISPLAY INVISIBLE (800 -9350);
FORCEPROP 0 LAST CDS_SEC 1
J 0
(800 -9350);
DISPLAY 0.680851 (800 -9350);
DISPLAY INVISIBLE (800 -9350);
FORCEPROP 1 LASTPIN (750 -9400) $PN 1
J 0
(760 -9415);
DISPLAY 0.787234 (760 -9415);
PAINT MONO (760 -9415);
FORCEPROP 1 LASTPIN (750 -9600) $PN 2
J 0
(760 -9615);
DISPLAY 0.787234 (760 -9615);
PAINT MONO (760 -9615);
FORCEPROP 1 LAST MATERIAL ALUM
J 0
(800 -9600);
DISPLAY 0.510638 (800 -9600);
FORCEPROP 1 LAST PACK_TYPE SMLF
J 0
(800 -9650);
DISPLAY 0.510638 (800 -9650);
FORCEPROP 1 LAST TOLERANCE 20%
J 0
(800 -9500);
DISPLAY 0.510638 (800 -9500);
FORCEPROP 1 LAST VOLTAGE 2.5V
J 0
(800 -9550);
DISPLAY 0.510638 (800 -9550);
FORCEPROP 1 LAST VALUE 390UF
J 0
(800 -9450);
DISPLAY 0.510638 (800 -9450);
FORCEPROP 2 LAST CDS_LIB pure_quanta
J 0
(750 -9500);
DISPLAY INVISIBLE (750 -9500);
FORCEPROP 1 LAST PART_NUMBER CC7390JMZ13
J 0
(800 -9700);
DISPLAY 0.510638 (800 -9700);
DISPLAY INVISIBLE (800 -9700);
FORCEPROP 1 LAST PATH I236
J 0
(800 -9350);
DISPLAY 0.978723 (800 -9350);
DISPLAY INVISIBLE (800 -9350);
FORCEADD UNIVERSAL_GND..1
(325 -8825);
FORCEPROP 3 LASTPIN (325 -8775) SIG_NAME GND\g
J 0
(335 -8765);
DISPLAY 0.659574 (335 -8765);
PAINT MONO (335 -8765);
DISPLAY INVISIBLE (335 -8765);
FORCEPROP 2 LAST CDS_LIB pure_quanta_power
J 0
(325 -8825);
DISPLAY INVISIBLE (325 -8825);
FORCEPROP 1 LAST HDL_POWER GND
J 1
(350 -8900);
DISPLAY 0.872340 (350 -8900);
PAINT GREEN (350 -8900);
DISPLAY INVISIBLE (350 -8900);
FORCEPROP 1 LAST PATH I237
J 0
(400 -8825);
DISPLAY 0.872340 (400 -8825);
PAINT AQUA (400 -8825);
DISPLAY INVISIBLE (400 -8825);
FORCEADD Q_CAPP..1
(500 -9500);
FORCEPROP 1 LAST LOCATION PC6573
J 0
(550 -9400);
DISPLAY 0.638298 (550 -9400);
FORCEPROP 0 LAST $SEC 1
J 0
(550 -9350);
DISPLAY 0.680851 (550 -9350);
PAINT MONO (550 -9350);
DISPLAY INVISIBLE (550 -9350);
FORCEPROP 0 LAST CDS_SEC 1
J 0
(550 -9350);
DISPLAY 0.680851 (550 -9350);
DISPLAY INVISIBLE (550 -9350);
FORCEPROP 1 LASTPIN (500 -9400) $PN 1
J 0
(510 -9415);
DISPLAY 0.787234 (510 -9415);
PAINT MONO (510 -9415);
FORCEPROP 1 LASTPIN (500 -9600) $PN 2
J 0
(510 -9615);
DISPLAY 0.787234 (510 -9615);
PAINT MONO (510 -9615);
FORCEPROP 1 LAST VOLTAGE 2.5V
J 0
(550 -9550);
DISPLAY 0.510638 (550 -9550);
FORCEPROP 1 LAST MATERIAL ALUM
J 0
(550 -9600);
DISPLAY 0.510638 (550 -9600);
FORCEPROP 1 LAST PACK_TYPE SMLF
J 0
(550 -9650);
DISPLAY 0.510638 (550 -9650);
FORCEPROP 1 LAST TOLERANCE 20%
J 0
(550 -9500);
DISPLAY 0.510638 (550 -9500);
FORCEPROP 1 LAST VALUE 390UF
J 0
(550 -9450);
DISPLAY 0.510638 (550 -9450);
FORCEPROP 2 LAST CDS_LIB pure_quanta
J 0
(500 -9500);
DISPLAY INVISIBLE (500 -9500);
FORCEPROP 1 LAST PART_NUMBER CC7390JMZ13
J 0
(550 -9700);
DISPLAY 0.510638 (550 -9700);
DISPLAY INVISIBLE (550 -9700);
FORCEPROP 1 LAST PATH I238
J 0
(550 -9350);
DISPLAY 0.978723 (550 -9350);
DISPLAY INVISIBLE (550 -9350);
FORCEADD Q_CAPP..1
(175 -9500);
FORCEPROP 1 LAST LOCATION PC534
J 0
(225 -9400);
DISPLAY 0.638298 (225 -9400);
FORCEPROP 0 LAST $SEC 1
J 0
(225 -9350);
DISPLAY 0.680851 (225 -9350);
PAINT MONO (225 -9350);
DISPLAY INVISIBLE (225 -9350);
FORCEPROP 0 LAST CDS_SEC 1
J 0
(225 -9350);
DISPLAY 0.680851 (225 -9350);
DISPLAY INVISIBLE (225 -9350);
FORCEPROP 1 LASTPIN (175 -9400) $PN 1
J 0
(185 -9415);
DISPLAY 0.787234 (185 -9415);
PAINT MONO (185 -9415);
FORCEPROP 1 LASTPIN (175 -9600) $PN 2
J 0
(185 -9615);
DISPLAY 0.787234 (185 -9615);
PAINT MONO (185 -9615);
FORCEPROP 1 LAST VALUE 470UF
J 0
(225 -9450);
DISPLAY 0.510638 (225 -9450);
FORCEPROP 1 LAST MATERIAL SPCAP
J 0
(225 -9600);
DISPLAY 0.510638 (225 -9600);
FORCEPROP 1 LAST TOLERANCE 20%
J 0
(225 -9500);
DISPLAY 0.510638 (225 -9500);
FORCEPROP 1 LAST VOLTAGE 2.5V
J 0
(225 -9550);
DISPLAY 0.510638 (225 -9550);
FORCEPROP 1 LAST PACK_TYPE SMLF
J 0
(225 -9650);
DISPLAY 0.510638 (225 -9650);
FORCEPROP 2 LAST CDS_LIB pure_quanta
J 0
(175 -9500);
DISPLAY INVISIBLE (175 -9500);
FORCEPROP 1 LAST PART_NUMBER CH747LM8818
J 0
(225 -9700);
DISPLAY 0.510638 (225 -9700);
DISPLAY INVISIBLE (225 -9700);
FORCEPROP 1 LAST PATH I239
J 0
(225 -9350);
DISPLAY 0.978723 (225 -9350);
DISPLAY INVISIBLE (225 -9350);
FORCEADD Q_CAP..1
(-1500 -5650);
FORCEPROP 1 LAST LOCATION PC6557_1
J 0
(-1450 -5550);
DISPLAY 0.787234 (-1450 -5550);
FORCEPROP 0 LAST $SEC 1
J 0
(-1450 -5500);
DISPLAY 0.680851 (-1450 -5500);
PAINT MONO (-1450 -5500);
DISPLAY INVISIBLE (-1450 -5500);
FORCEPROP 0 LAST CDS_SEC 1
J 0
(-1425 -5425);
DISPLAY 0.680851 (-1425 -5425);
PAINT MONO (-1425 -5425);
DISPLAY INVISIBLE (-1425 -5425);
FORCEPROP 1 LASTPIN (-1500 -5550) $PN 1
J 0
(-1490 -5570);
DISPLAY 0.787234 (-1490 -5570);
PAINT MONO (-1490 -5570);
FORCEPROP 1 LASTPIN (-1500 -5750) $PN 2
J 0
(-1490 -5770);
DISPLAY 0.787234 (-1490 -5770);
PAINT MONO (-1490 -5770);
FORCEPROP 1 LAST TOLERANCE 20%
J 0
(-1450 -5700);
DISPLAY 0.638298 (-1450 -5700);
FORCEPROP 1 LAST MATERIAL X6S
J 0
(-1450 -5750);
DISPLAY 0.638298 (-1450 -5750);
FORCEPROP 1 LAST VOLTAGE 16V
J 0
(-1450 -5650);
DISPLAY 0.638298 (-1450 -5650);
FORCEPROP 1 LAST PACK_TYPE C0805
J 0
(-1450 -5850);
DISPLAY 0.638298 (-1450 -5850);
FORCEPROP 1 LAST VALUE 22UF
J 0
(-1450 -5600);
DISPLAY 0.638298 (-1450 -5600);
FORCEPROP 2 LAST CDS_LIB pure_quanta
J 0
(-1500 -5650);
DISPLAY INVISIBLE (-1500 -5650);
FORCEPROP 2 LAST BOM_COST VR_DIMM 
J 0
(-1450 -5500);
DISPLAY 0.680851 (-1450 -5500);
DISPLAY INVISIBLE (-1450 -5500);
FORCEPROP 0 LAST REUSE_ID 41
J 0
(-1450 -5450);
DISPLAY 0.680851 (-1450 -5450);
DISPLAY INVISIBLE (-1450 -5450);
FORCEPROP 1 LAST PART_NUMBER CH6223MEA01
J 0
(-1450 -5800);
DISPLAY 0.638298 (-1450 -5800);
DISPLAY INVISIBLE (-1450 -5800);
FORCEPROP 1 LAST PATH I24
J 0
(-1450 -5500);
DISPLAY 0.978723 (-1450 -5500);
PAINT WHITE (-1450 -5500);
DISPLAY INVISIBLE (-1450 -5500);
FORCEADD UNIVERSAL_GND..1
(750 -9850);
FORCEPROP 3 LASTPIN (750 -9800) SIG_NAME GND\g
J 0
(760 -9790);
DISPLAY 0.659574 (760 -9790);
PAINT MONO (760 -9790);
DISPLAY INVISIBLE (760 -9790);
FORCEPROP 2 LAST CDS_LIB pure_quanta_power
J 0
(750 -9850);
DISPLAY INVISIBLE (750 -9850);
FORCEPROP 1 LAST HDL_POWER GND
J 1
(775 -9925);
DISPLAY 0.872340 (775 -9925);
PAINT GREEN (775 -9925);
DISPLAY INVISIBLE (775 -9925);
FORCEPROP 1 LAST PATH I240
J 0
(825 -9850);
DISPLAY 0.872340 (825 -9850);
PAINT AQUA (825 -9850);
DISPLAY INVISIBLE (825 -9850);
FORCEADD Q_CAP..1
(-125 -8600);
FORCEPROP 1 LAST LOCATION PC6583
J 0
(-75 -8500);
DISPLAY 0.978723 (-75 -8500);
FORCEPROP 0 LAST $SEC 1
J 0
(-75 -8450);
DISPLAY 0.680851 (-75 -8450);
PAINT MONO (-75 -8450);
DISPLAY INVISIBLE (-75 -8450);
FORCEPROP 0 LAST CDS_SEC 1
J 0
(-75 -8450);
DISPLAY 0.680851 (-75 -8450);
DISPLAY INVISIBLE (-75 -8450);
FORCEPROP 1 LASTPIN (-125 -8500) $PN 1
J 0
(-115 -8520);
DISPLAY 0.787234 (-115 -8520);
PAINT MONO (-115 -8520);
FORCEPROP 1 LASTPIN (-125 -8700) $PN 2
J 0
(-115 -8720);
DISPLAY 0.787234 (-115 -8720);
PAINT MONO (-115 -8720);
FORCEPROP 1 LAST MATERIAL X6S
J 0
(-75 -8700);
DISPLAY 0.510638 (-75 -8700);
FORCEPROP 1 LAST TOLERANCE 20%
J 0
(-75 -8650);
DISPLAY 0.510638 (-75 -8650);
FORCEPROP 1 LAST VALUE 22UF
J 0
(-75 -8550);
DISPLAY 0.510638 (-75 -8550);
FORCEPROP 1 LAST PACK_TYPE C0805
J 0
(-75 -8800);
DISPLAY 0.510638 (-75 -8800);
FORCEPROP 1 LAST VOLTAGE 16V
J 0
(-75 -8600);
DISPLAY 0.510638 (-75 -8600);
FORCEPROP 2 LAST CDS_LIB pure_quanta
J 0
(-125 -8600);
DISPLAY INVISIBLE (-125 -8600);
FORCEPROP 1 LAST PART_NUMBER CH6223MEA01
J 0
(-75 -8750);
DISPLAY 0.510638 (-75 -8750);
DISPLAY INVISIBLE (-75 -8750);
FORCEPROP 1 LAST PATH I241
J 0
(-75 -8450);
DISPLAY 0.978723 (-75 -8450);
PAINT WHITE (-75 -8450);
DISPLAY INVISIBLE (-75 -8450);
FORCEADD Q_CAP..1
(-525 -8550);
FORCEPROP 1 LAST LOCATION PC6582_2
J 0
(-475 -8450);
DISPLAY 0.978723 (-475 -8450);
FORCEPROP 0 LAST $SEC 1
J 0
(-475 -8400);
DISPLAY 0.680851 (-475 -8400);
PAINT MONO (-475 -8400);
DISPLAY INVISIBLE (-475 -8400);
FORCEPROP 0 LAST CDS_SEC 1
J 0
(-475 -8400);
DISPLAY 0.680851 (-475 -8400);
DISPLAY INVISIBLE (-475 -8400);
FORCEPROP 1 LASTPIN (-525 -8450) $PN 1
J 0
(-515 -8470);
DISPLAY 0.787234 (-515 -8470);
PAINT MONO (-515 -8470);
FORCEPROP 1 LASTPIN (-525 -8650) $PN 2
J 0
(-515 -8670);
DISPLAY 0.787234 (-515 -8670);
PAINT MONO (-515 -8670);
FORCEPROP 1 LAST PACK_TYPE C0805
J 0
(-475 -8750);
DISPLAY 0.638298 (-475 -8750);
FORCEPROP 1 LAST TOLERANCE 20%
J 0
(-475 -8600);
DISPLAY 0.638298 (-475 -8600);
FORCEPROP 1 LAST VOLTAGE 16V
J 0
(-475 -8550);
DISPLAY 0.638298 (-475 -8550);
FORCEPROP 1 LAST VALUE 22UF
J 0
(-475 -8500);
DISPLAY 0.638298 (-475 -8500);
FORCEPROP 1 LAST MATERIAL X6S
J 0
(-475 -8650);
DISPLAY 0.638298 (-475 -8650);
FORCEPROP 0 LAST REUSE_ID 41
J 0
(-475 -8350);
DISPLAY 0.680851 (-475 -8350);
DISPLAY INVISIBLE (-475 -8350);
FORCEPROP 2 LAST BOM_COST VR_DIMM 
J 0
(-475 -8400);
DISPLAY 0.680851 (-475 -8400);
DISPLAY INVISIBLE (-475 -8400);
FORCEPROP 2 LAST CDS_LIB pure_quanta
J 0
(-525 -8550);
DISPLAY INVISIBLE (-525 -8550);
FORCEPROP 1 LAST PART_NUMBER CH6223MEA01
J 0
(-475 -8700);
DISPLAY 0.638298 (-475 -8700);
DISPLAY INVISIBLE (-475 -8700);
FORCEPROP 1 LAST PATH I242
J 0
(-475 -8400);
DISPLAY 0.978723 (-475 -8400);
PAINT WHITE (-475 -8400);
DISPLAY INVISIBLE (-475 -8400);
FORCEADD Q_CAP..1
(-900 -8550);
FORCEPROP 1 LAST LOCATION PC6581_2
J 0
(-850 -8450);
DISPLAY 0.978723 (-850 -8450);
FORCEPROP 0 LAST $SEC 1
J 0
(-850 -8400);
DISPLAY 0.680851 (-850 -8400);
PAINT MONO (-850 -8400);
DISPLAY INVISIBLE (-850 -8400);
FORCEPROP 0 LAST CDS_SEC 1
J 0
(-850 -8400);
DISPLAY 0.680851 (-850 -8400);
DISPLAY INVISIBLE (-850 -8400);
FORCEPROP 1 LASTPIN (-900 -8450) $PN 1
J 0
(-890 -8470);
DISPLAY 0.787234 (-890 -8470);
PAINT MONO (-890 -8470);
FORCEPROP 1 LASTPIN (-900 -8650) $PN 2
J 0
(-890 -8670);
DISPLAY 0.787234 (-890 -8670);
PAINT MONO (-890 -8670);
FORCEPROP 1 LAST VALUE 22UF
J 0
(-850 -8500);
DISPLAY 0.638298 (-850 -8500);
FORCEPROP 1 LAST VOLTAGE 16V
J 0
(-850 -8550);
DISPLAY 0.638298 (-850 -8550);
FORCEPROP 1 LAST TOLERANCE 20%
J 0
(-850 -8600);
DISPLAY 0.638298 (-850 -8600);
FORCEPROP 1 LAST PACK_TYPE C0805
J 0
(-850 -8750);
DISPLAY 0.638298 (-850 -8750);
FORCEPROP 1 LAST MATERIAL X6S
J 0
(-850 -8650);
DISPLAY 0.638298 (-850 -8650);
FORCEPROP 2 LAST CDS_LIB pure_quanta
J 0
(-900 -8550);
DISPLAY INVISIBLE (-900 -8550);
FORCEPROP 0 LAST REUSE_ID 41
J 0
(-850 -8350);
DISPLAY 0.680851 (-850 -8350);
DISPLAY INVISIBLE (-850 -8350);
FORCEPROP 2 LAST BOM_COST VR_DIMM 
J 0
(-850 -8400);
DISPLAY 0.680851 (-850 -8400);
DISPLAY INVISIBLE (-850 -8400);
FORCEPROP 1 LAST PART_NUMBER CH6223MEA01
J 0
(-850 -8700);
DISPLAY 0.638298 (-850 -8700);
DISPLAY INVISIBLE (-850 -8700);
FORCEPROP 1 LAST PATH I243
J 0
(-850 -8400);
DISPLAY 0.978723 (-850 -8400);
PAINT WHITE (-850 -8400);
DISPLAY INVISIBLE (-850 -8400);
FORCEADD Q_CAP..1
(-1375 -8550);
FORCEPROP 1 LAST LOCATION PC6580_2
J 0
(-1325 -8450);
DISPLAY 0.978723 (-1325 -8450);
FORCEPROP 0 LAST $SEC 1
J 0
(-1325 -8400);
DISPLAY 0.680851 (-1325 -8400);
PAINT MONO (-1325 -8400);
DISPLAY INVISIBLE (-1325 -8400);
FORCEPROP 0 LAST CDS_SEC 1
J 0
(-1325 -8400);
DISPLAY 0.680851 (-1325 -8400);
DISPLAY INVISIBLE (-1325 -8400);
FORCEPROP 1 LASTPIN (-1375 -8450) $PN 1
J 0
(-1365 -8470);
DISPLAY 0.787234 (-1365 -8470);
PAINT MONO (-1365 -8470);
FORCEPROP 1 LASTPIN (-1375 -8650) $PN 2
J 0
(-1365 -8670);
DISPLAY 0.787234 (-1365 -8670);
PAINT MONO (-1365 -8670);
FORCEPROP 1 LAST TOLERANCE 20%
J 0
(-1325 -8600);
DISPLAY 0.638298 (-1325 -8600);
FORCEPROP 1 LAST VOLTAGE 16V
J 0
(-1325 -8550);
DISPLAY 0.638298 (-1325 -8550);
FORCEPROP 1 LAST VALUE 22UF
J 0
(-1325 -8500);
DISPLAY 0.638298 (-1325 -8500);
FORCEPROP 1 LAST MATERIAL X6S
J 0
(-1325 -8650);
DISPLAY 0.638298 (-1325 -8650);
FORCEPROP 1 LAST PACK_TYPE C0805
J 0
(-1325 -8750);
DISPLAY 0.638298 (-1325 -8750);
FORCEPROP 0 LAST REUSE_ID 41
J 0
(-1325 -8350);
DISPLAY 0.680851 (-1325 -8350);
DISPLAY INVISIBLE (-1325 -8350);
FORCEPROP 2 LAST BOM_COST VR_DIMM 
J 0
(-1325 -8400);
DISPLAY 0.680851 (-1325 -8400);
DISPLAY INVISIBLE (-1325 -8400);
FORCEPROP 2 LAST CDS_LIB pure_quanta
J 0
(-1375 -8550);
DISPLAY INVISIBLE (-1375 -8550);
FORCEPROP 1 LAST PART_NUMBER CH6223MEA01
J 0
(-1325 -8700);
DISPLAY 0.638298 (-1325 -8700);
DISPLAY INVISIBLE (-1325 -8700);
FORCEPROP 1 LAST PATH I244
J 0
(-1325 -8400);
DISPLAY 0.978723 (-1325 -8400);
PAINT WHITE (-1325 -8400);
DISPLAY INVISIBLE (-1325 -8400);
FORCEADD Q_CAP..1
(-1875 -8550);
FORCEPROP 1 LAST LOCATION PC6579_2
J 0
(-1825 -8450);
DISPLAY 0.978723 (-1825 -8450);
FORCEPROP 0 LAST $SEC 1
J 0
(-1825 -8400);
DISPLAY 0.680851 (-1825 -8400);
PAINT MONO (-1825 -8400);
DISPLAY INVISIBLE (-1825 -8400);
FORCEPROP 0 LAST CDS_SEC 1
J 0
(-1825 -8400);
DISPLAY 0.680851 (-1825 -8400);
DISPLAY INVISIBLE (-1825 -8400);
FORCEPROP 1 LASTPIN (-1875 -8450) $PN 1
J 0
(-1865 -8470);
DISPLAY 0.787234 (-1865 -8470);
PAINT MONO (-1865 -8470);
FORCEPROP 1 LASTPIN (-1875 -8650) $PN 2
J 0
(-1865 -8670);
DISPLAY 0.787234 (-1865 -8670);
PAINT MONO (-1865 -8670);
FORCEPROP 1 LAST TOLERANCE 20%
J 0
(-1825 -8600);
DISPLAY 0.638298 (-1825 -8600);
FORCEPROP 1 LAST MATERIAL X6S
J 0
(-1825 -8650);
DISPLAY 0.638298 (-1825 -8650);
FORCEPROP 1 LAST VOLTAGE 16V
J 0
(-1825 -8550);
DISPLAY 0.638298 (-1825 -8550);
FORCEPROP 1 LAST VALUE 22UF
J 0
(-1825 -8500);
DISPLAY 0.638298 (-1825 -8500);
FORCEPROP 1 LAST PACK_TYPE C0805
J 0
(-1825 -8750);
DISPLAY 0.638298 (-1825 -8750);
FORCEPROP 2 LAST CDS_LIB pure_quanta
J 0
(-1875 -8550);
DISPLAY INVISIBLE (-1875 -8550);
FORCEPROP 2 LAST BOM_COST VR_DIMM 
J 0
(-1825 -8400);
DISPLAY 0.680851 (-1825 -8400);
DISPLAY INVISIBLE (-1825 -8400);
FORCEPROP 0 LAST REUSE_ID 41
J 0
(-1825 -8350);
DISPLAY 0.680851 (-1825 -8350);
DISPLAY INVISIBLE (-1825 -8350);
FORCEPROP 1 LAST PART_NUMBER CH6223MEA01
J 0
(-1825 -8700);
DISPLAY 0.638298 (-1825 -8700);
DISPLAY INVISIBLE (-1825 -8700);
FORCEPROP 1 LAST PATH I245
J 0
(-1825 -8400);
DISPLAY 0.978723 (-1825 -8400);
PAINT WHITE (-1825 -8400);
DISPLAY INVISIBLE (-1825 -8400);
FORCEADD UNIVERSAL_GND..1
(-125 -8825);
FORCEPROP 3 LASTPIN (-125 -8775) SIG_NAME GND\g
J 0
(-115 -8765);
DISPLAY 0.659574 (-115 -8765);
PAINT MONO (-115 -8765);
DISPLAY INVISIBLE (-115 -8765);
FORCEPROP 2 LAST CDS_LIB pure_quanta_power
J 0
(-125 -8825);
DISPLAY INVISIBLE (-125 -8825);
FORCEPROP 1 LAST HDL_POWER GND
J 1
(-100 -8900);
DISPLAY 0.872340 (-100 -8900);
PAINT GREEN (-100 -8900);
DISPLAY INVISIBLE (-100 -8900);
FORCEPROP 1 LAST PATH I246
J 0
(-50 -8825);
DISPLAY 0.872340 (-50 -8825);
PAINT AQUA (-50 -8825);
DISPLAY INVISIBLE (-50 -8825);
FORCEADD Q_CAPP..1
(-25 -9500);
FORCEPROP 1 LAST LOCATION PC6811
J 0
(25 -9400);
DISPLAY 0.638298 (25 -9400);
FORCEPROP 0 LAST $SEC 1
J 0
(25 -9350);
DISPLAY 0.680851 (25 -9350);
PAINT MONO (25 -9350);
DISPLAY INVISIBLE (25 -9350);
FORCEPROP 0 LAST CDS_SEC 1
J 0
(25 -9350);
DISPLAY 0.680851 (25 -9350);
DISPLAY INVISIBLE (25 -9350);
FORCEPROP 1 LASTPIN (-25 -9400) $PN 1
J 0
(-15 -9415);
DISPLAY 0.787234 (-15 -9415);
PAINT MONO (-15 -9415);
FORCEPROP 1 LASTPIN (-25 -9600) $PN 2
J 0
(-15 -9615);
DISPLAY 0.787234 (-15 -9615);
PAINT MONO (-15 -9615);
FORCEPROP 1 LAST TOLERANCE 20%
J 0
(25 -9500);
DISPLAY 0.510638 (25 -9500);
FORCEPROP 1 LAST VALUE 470UF
J 0
(25 -9450);
DISPLAY 0.510638 (25 -9450);
FORCEPROP 1 LAST VOLTAGE 2.5V
J 0
(25 -9550);
DISPLAY 0.510638 (25 -9550);
FORCEPROP 1 LAST MATERIAL SPCAP
J 0
(25 -9600);
DISPLAY 0.510638 (25 -9600);
FORCEPROP 1 LAST PACK_TYPE SMLF
J 0
(25 -9650);
DISPLAY 0.510638 (25 -9650);
FORCEPROP 2 LAST CDS_LIB pure_quanta
J 0
(-25 -9500);
DISPLAY INVISIBLE (-25 -9500);
FORCEPROP 1 LAST PART_NUMBER CH747LM8818
J 0
(25 -9700);
DISPLAY 0.510638 (25 -9700);
DISPLAY INVISIBLE (25 -9700);
FORCEPROP 1 LAST PATH I247
J 0
(25 -9350);
DISPLAY 0.978723 (25 -9350);
DISPLAY INVISIBLE (25 -9350);
FORCEADD Q_CAPP..1
(-250 -9500);
FORCEPROP 1 LAST LOCATION PC6812
J 0
(-200 -9400);
DISPLAY 0.510638 (-200 -9400);
FORCEPROP 0 LAST $SEC 1
J 0
(-200 -9375);
DISPLAY 0.680851 (-200 -9375);
PAINT MONO (-200 -9375);
DISPLAY INVISIBLE (-200 -9375);
FORCEPROP 0 LAST CDS_SEC 1
J 0
(-200 -9375);
DISPLAY 0.680851 (-200 -9375);
DISPLAY INVISIBLE (-200 -9375);
FORCEPROP 1 LASTPIN (-250 -9400) $PN 1
J 0
(-240 -9415);
DISPLAY 0.787234 (-240 -9415);
PAINT MONO (-240 -9415);
FORCEPROP 1 LASTPIN (-250 -9600) $PN 2
J 0
(-240 -9615);
DISPLAY 0.787234 (-240 -9615);
PAINT MONO (-240 -9615);
FORCEPROP 1 LAST TOLERANCE 20%
J 0
(-200 -9500);
DISPLAY 0.510638 (-200 -9500);
FORCEPROP 1 LAST VALUE 470UF
J 0
(-200 -9450);
DISPLAY 0.510638 (-200 -9450);
FORCEPROP 1 LAST VOLTAGE 2.5V
J 0
(-200 -9550);
DISPLAY 0.510638 (-200 -9550);
FORCEPROP 1 LAST MATERIAL SPCAP
J 0
(-200 -9600);
DISPLAY 0.510638 (-200 -9600);
FORCEPROP 1 LAST PACK_TYPE SMLF
J 0
(-200 -9650);
DISPLAY 0.510638 (-200 -9650);
FORCEPROP 2 LAST CDS_LIB pure_quanta
J 0
(-250 -9500);
DISPLAY INVISIBLE (-250 -9500);
FORCEPROP 1 LAST PART_NUMBER CH747LM8818
J 0
(-200 -9700);
DISPLAY 0.510638 (-200 -9700);
DISPLAY INVISIBLE (-200 -9700);
FORCEPROP 1 LAST PATH I248
J 0
(-200 -9350);
DISPLAY 0.978723 (-200 -9350);
DISPLAY INVISIBLE (-200 -9350);
FORCEADD UNIVERSAL_GND..1
(-525 -8825);
FORCEPROP 3 LASTPIN (-525 -8775) SIG_NAME GND\g
J 0
(-515 -8765);
DISPLAY 0.659574 (-515 -8765);
PAINT MONO (-515 -8765);
DISPLAY INVISIBLE (-515 -8765);
FORCEPROP 2 LAST CDS_LIB pure_quanta_power
J 0
(-525 -8825);
DISPLAY INVISIBLE (-525 -8825);
FORCEPROP 1 LAST HDL_POWER GND
J 1
(-500 -8900);
DISPLAY 0.872340 (-500 -8900);
PAINT GREEN (-500 -8900);
DISPLAY INVISIBLE (-500 -8900);
FORCEPROP 1 LAST PATH I249
J 0
(-450 -8825);
DISPLAY 0.872340 (-450 -8825);
PAINT AQUA (-450 -8825);
DISPLAY INVISIBLE (-450 -8825);
FORCEADD Q_CAP..1
(-475 -9500);
FORCEPROP 1 LAST LOCATION PC6587_2
J 0
(-450 -9400);
DISPLAY 0.638298 (-450 -9400);
FORCEPROP 0 LAST $SEC 1
J 0
(-450 -9350);
DISPLAY 0.680851 (-450 -9350);
PAINT MONO (-450 -9350);
DISPLAY INVISIBLE (-450 -9350);
FORCEPROP 0 LAST CDS_SEC 1
J 0
(-450 -9350);
DISPLAY 0.680851 (-450 -9350);
DISPLAY INVISIBLE (-450 -9350);
FORCEPROP 1 LASTPIN (-475 -9400) $PN 1
J 0
(-465 -9420);
DISPLAY 0.787234 (-465 -9420);
PAINT MONO (-465 -9420);
FORCEPROP 1 LASTPIN (-475 -9600) $PN 2
J 0
(-465 -9620);
DISPLAY 0.787234 (-465 -9620);
PAINT MONO (-465 -9620);
FORCEPROP 1 LAST TOLERANCE 20%
J 0
(-425 -9550);
DISPLAY 0.510638 (-425 -9550);
FORCEPROP 1 LAST VOLTAGE 4V
J 0
(-425 -9500);
DISPLAY 0.510638 (-425 -9500);
FORCEPROP 1 LAST VALUE 22UF
J 0
(-425 -9450);
DISPLAY 0.510638 (-425 -9450);
FORCEPROP 1 LAST MATERIAL X6S
J 0
(-425 -9600);
DISPLAY 0.510638 (-425 -9600);
FORCEPROP 1 LAST PACK_TYPE C0805
J 0
(-425 -9650);
DISPLAY 0.510638 (-425 -9650);
FORCEPROP 2 LAST CDS_LIB pure_quanta
J 0
(-475 -9500);
DISPLAY INVISIBLE (-475 -9500);
FORCEPROP 1 LAST PART_NUMBER CH622KMEA03
J 0
(-425 -9650);
DISPLAY 0.510638 (-425 -9650);
DISPLAY INVISIBLE (-425 -9650);
FORCEPROP 1 LAST PATH I250
J 0
(-425 -9350);
DISPLAY 0.978723 (-425 -9350);
PAINT WHITE (-425 -9350);
DISPLAY INVISIBLE (-425 -9350);
FORCEADD Q_CAP..1
(-700 -9500);
FORCEPROP 1 LAST LOCATION PC6586_2
J 0
(-675 -9400);
DISPLAY 0.638298 (-675 -9400);
FORCEPROP 0 LAST $SEC 1
J 0
(-675 -9350);
DISPLAY 0.680851 (-675 -9350);
PAINT MONO (-675 -9350);
DISPLAY INVISIBLE (-675 -9350);
FORCEPROP 0 LAST CDS_SEC 1
J 0
(-675 -9350);
DISPLAY 0.680851 (-675 -9350);
DISPLAY INVISIBLE (-675 -9350);
FORCEPROP 1 LASTPIN (-700 -9400) $PN 1
J 0
(-690 -9420);
DISPLAY 0.787234 (-690 -9420);
PAINT MONO (-690 -9420);
FORCEPROP 1 LASTPIN (-700 -9600) $PN 2
J 0
(-690 -9620);
DISPLAY 0.787234 (-690 -9620);
PAINT MONO (-690 -9620);
FORCEPROP 1 LAST MATERIAL X6S
J 0
(-650 -9600);
DISPLAY 0.510638 (-650 -9600);
FORCEPROP 1 LAST PACK_TYPE C0805
J 0
(-650 -9650);
DISPLAY 0.510638 (-650 -9650);
FORCEPROP 1 LAST VOLTAGE 4V
J 0
(-650 -9500);
DISPLAY 0.510638 (-650 -9500);
FORCEPROP 1 LAST VALUE 22UF
J 0
(-650 -9450);
DISPLAY 0.510638 (-650 -9450);
FORCEPROP 1 LAST TOLERANCE 20%
J 0
(-650 -9550);
DISPLAY 0.510638 (-650 -9550);
FORCEPROP 2 LAST CDS_LIB pure_quanta
J 0
(-700 -9500);
DISPLAY INVISIBLE (-700 -9500);
FORCEPROP 1 LAST PART_NUMBER CH622KMEA03
J 0
(-650 -9700);
DISPLAY 0.510638 (-650 -9700);
DISPLAY INVISIBLE (-650 -9700);
FORCEPROP 1 LAST PATH I251
J 0
(-650 -9350);
DISPLAY 0.978723 (-650 -9350);
PAINT WHITE (-650 -9350);
DISPLAY INVISIBLE (-650 -9350);
FORCEADD UNIVERSAL_GND..1
(-900 -8825);
FORCEPROP 3 LASTPIN (-900 -8775) SIG_NAME GND\g
J 0
(-890 -8765);
DISPLAY 0.659574 (-890 -8765);
PAINT MONO (-890 -8765);
DISPLAY INVISIBLE (-890 -8765);
FORCEPROP 2 LAST CDS_LIB pure_quanta_power
J 0
(-900 -8825);
DISPLAY INVISIBLE (-900 -8825);
FORCEPROP 1 LAST HDL_POWER GND
J 1
(-875 -8900);
DISPLAY 0.872340 (-875 -8900);
PAINT GREEN (-875 -8900);
DISPLAY INVISIBLE (-875 -8900);
FORCEPROP 1 LAST PATH I252
J 0
(-825 -8825);
DISPLAY 0.872340 (-825 -8825);
PAINT AQUA (-825 -8825);
DISPLAY INVISIBLE (-825 -8825);
FORCEADD Q_CAP..2
(-1000 -9000);
FORCEPROP 1 LAST LOCATION PC6584
J 1
(-1000 -8900);
DISPLAY 0.978723 (-1000 -8900);
FORCEPROP 0 LAST $SEC 1
J 0
(-1000 -8850);
DISPLAY 0.680851 (-1000 -8850);
PAINT MONO (-1000 -8850);
DISPLAY INVISIBLE (-1000 -8850);
FORCEPROP 0 LAST CDS_SEC 1
J 0
(-1000 -8850);
DISPLAY 0.680851 (-1000 -8850);
DISPLAY INVISIBLE (-1000 -8850);
FORCEPROP 1 LASTPIN (-1100 -9000) $PN 1
J 0
(-1110 -8985);
DISPLAY 0.787234 (-1110 -8985);
PAINT MONO (-1110 -8985);
FORCEPROP 1 LASTPIN (-900 -9000) $PN 2
J 0
(-915 -8985);
DISPLAY 0.787234 (-915 -8985);
PAINT MONO (-915 -8985);
FORCEPROP 1 LAST VALUE 100NF
J 2
(-1000 -9100);
DISPLAY 0.617021 (-1000 -9100);
FORCEPROP 1 LAST MATERIAL X7R
J 0
(-1000 -9150);
DISPLAY 0.617021 (-1000 -9150);
FORCEPROP 1 LAST TOLERANCE 10%
J 2
(-1000 -9150);
DISPLAY 0.617021 (-1000 -9150);
FORCEPROP 1 LAST VOLTAGE 50V
J 0
(-1000 -9100);
DISPLAY 0.617021 (-1000 -9100);
FORCEPROP 1 LAST PACK_TYPE C0402
J 1
(-1000 -9200);
DISPLAY 0.617021 (-1000 -9200);
FORCEPROP 2 LAST CDS_LIB pure_quanta
J 0
(-1000 -9000);
DISPLAY INVISIBLE (-1000 -9000);
FORCEPROP 0 LAST REUSE_ID 55
J 0
(-1025 -8900);
DISPLAY 0.680851 (-1025 -8900);
DISPLAY INVISIBLE (-1025 -8900);
FORCEPROP 2 LAST BOM_COST VR_DIMM 
J 0
(-1000 -8850);
DISPLAY 0.680851 (-1000 -8850);
DISPLAY INVISIBLE (-1000 -8850);
FORCEPROP 1 LAST PART_NUMBER CH4106K1B01
J 1
(-1000 -8950);
DISPLAY 0.617021 (-1000 -8950);
DISPLAY INVISIBLE (-1000 -8950);
FORCEPROP 1 LAST PATH I253
J 0
(-1000 -8800);
DISPLAY 0.978723 (-1000 -8800);
PAINT WHITE (-1000 -8800);
DISPLAY INVISIBLE (-1000 -8800);
FORCEADD UNIVERSAL_GND..1
(-1375 -8825);
FORCEPROP 3 LASTPIN (-1375 -8775) SIG_NAME GND\g
J 0
(-1365 -8765);
DISPLAY 0.659574 (-1365 -8765);
PAINT MONO (-1365 -8765);
DISPLAY INVISIBLE (-1365 -8765);
FORCEPROP 2 LAST CDS_LIB pure_quanta_power
J 0
(-1375 -8825);
DISPLAY INVISIBLE (-1375 -8825);
FORCEPROP 1 LAST HDL_POWER GND
J 1
(-1350 -8900);
DISPLAY 0.872340 (-1350 -8900);
PAINT GREEN (-1350 -8900);
DISPLAY INVISIBLE (-1350 -8900);
FORCEPROP 1 LAST PATH I254
J 0
(-1300 -8825);
DISPLAY 0.872340 (-1300 -8825);
PAINT AQUA (-1300 -8825);
DISPLAY INVISIBLE (-1300 -8825);
FORCEADD Q_CAP..1
(-1025 -9500);
FORCEPROP 1 LAST LOCATION PC6806
J 0
(-975 -9400);
DISPLAY 0.978723 (-975 -9400);
FORCEPROP 0 LAST $SEC 1
J 0
(-975 -9350);
DISPLAY 0.680851 (-975 -9350);
PAINT MONO (-975 -9350);
DISPLAY INVISIBLE (-975 -9350);
FORCEPROP 0 LAST CDS_SEC 1
J 0
(-975 -9350);
DISPLAY 0.680851 (-975 -9350);
DISPLAY INVISIBLE (-975 -9350);
FORCEPROP 1 LASTPIN (-1025 -9400) $PN 1
J 0
(-1015 -9420);
DISPLAY 0.787234 (-1015 -9420);
PAINT MONO (-1015 -9420);
FORCEPROP 1 LASTPIN (-1025 -9600) $PN 2
J 0
(-1015 -9620);
DISPLAY 0.787234 (-1015 -9620);
PAINT MONO (-1015 -9620);
FORCEPROP 1 LAST TOLERANCE 10%
J 0
(-975 -9550);
DISPLAY 0.489362 (-975 -9550);
FORCEPROP 1 LAST PACK_TYPE C0402
J 0
(-975 -9700);
DISPLAY 0.489362 (-975 -9700);
FORCEPROP 1 LAST MATERIAL X7R
J 0
(-975 -9600);
DISPLAY 0.489362 (-975 -9600);
FORCEPROP 1 LAST VOLTAGE 50V
J 0
(-975 -9500);
DISPLAY 0.489362 (-975 -9500);
FORCEPROP 1 LAST VALUE 100NF
J 0
(-975 -9450);
DISPLAY 0.489362 (-975 -9450);
FORCEPROP 2 LAST BOM_COST VR_DIMM 
J 0
(-975 -9350);
DISPLAY 0.680851 (-975 -9350);
DISPLAY INVISIBLE (-975 -9350);
FORCEPROP 2 LAST CDS_LIB pure_quanta
J 0
(-1025 -9500);
DISPLAY INVISIBLE (-1025 -9500);
FORCEPROP 1 LAST PART_NUMBER CH4106K1B01
J 0
(-975 -9650);
DISPLAY 0.489362 (-975 -9650);
DISPLAY INVISIBLE (-975 -9650);
FORCEPROP 1 LAST PATH I255
J 0
(-975 -9350);
DISPLAY 0.978723 (-975 -9350);
PAINT WHITE (-975 -9350);
DISPLAY INVISIBLE (-975 -9350);
FORCEADD UNIVERSAL_GND..1
(-1875 -8825);
FORCEPROP 3 LASTPIN (-1875 -8775) SIG_NAME GND\g
J 0
(-1865 -8765);
DISPLAY 0.659574 (-1865 -8765);
PAINT MONO (-1865 -8765);
DISPLAY INVISIBLE (-1865 -8765);
FORCEPROP 2 LAST CDS_LIB pure_quanta_power
J 0
(-1875 -8825);
DISPLAY INVISIBLE (-1875 -8825);
FORCEPROP 1 LAST HDL_POWER GND
J 1
(-1850 -8900);
DISPLAY 0.872340 (-1850 -8900);
PAINT GREEN (-1850 -8900);
DISPLAY INVISIBLE (-1850 -8900);
FORCEPROP 1 LAST PATH I256
J 0
(-1800 -8825);
DISPLAY 0.872340 (-1800 -8825);
PAINT AQUA (-1800 -8825);
DISPLAY INVISIBLE (-1800 -8825);
FORCEADD Q_INDUCTOR..1
(-1825 -9325);
FORCEPROP 1 LAST LOCATION PL6506
J 0
(-2150 -9300);
DISPLAY 0.723404 (-2150 -9300);
PAINT GREEN (-2150 -9300);
FORCEPROP 0 LAST $SEC 1
J 0
(-2150 -9250);
DISPLAY 0.680851 (-2150 -9250);
PAINT MONO (-2150 -9250);
DISPLAY INVISIBLE (-2150 -9250);
FORCEPROP 0 LAST CDS_SEC 1
J 0
(-2150 -9250);
DISPLAY 0.680851 (-2150 -9250);
DISPLAY INVISIBLE (-2150 -9250);
FORCEPROP 0 LASTPIN (-1925 -9350) $PN 1
J 2
(-1935 -9340);
DISPLAY 0.680851 (-1935 -9340);
PAINT MONO (-1935 -9340);
FORCEPROP 0 LASTPIN (-1725 -9350) $PN 2
J 0
(-1715 -9340);
DISPLAY 0.680851 (-1715 -9340);
PAINT MONO (-1715 -9340);
FORCEPROP 2 LAST PACK_TYPE SMLF
J 0
(-1500 -9400);
DISPLAY 0.617021 (-1500 -9400);
FORCEPROP 2 LAST VALUE 120NH/69A
J 0
(-1650 -9325);
DISPLAY 0.617021 (-1650 -9325);
FORCEPROP 1 LAST MATERIAL IND
J 0
(-2125 -9350);
DISPLAY 0.723404 (-2125 -9350);
PAINT GREEN (-2125 -9350);
FORCEPROP 1 LAST NEEDS_NO_SIZE TRUE
J 0
(-1825 -9325);
DISPLAY 0.468085 (-1825 -9325);
PAINT GREEN (-1825 -9325);
DISPLAY INVISIBLE (-1825 -9325);
FORCEPROP 2 LAST BOM_COST VR_DIMM 
J 0
(-1650 -9275);
DISPLAY 0.680851 (-1650 -9275);
DISPLAY INVISIBLE (-1650 -9275);
FORCEPROP 2 LAST CDS_LIB pure_quanta
J 0
(-1825 -9325);
DISPLAY INVISIBLE (-1825 -9325);
FORCEPROP 1 LAST PART_NUMBER CV+12^0EZ03
J 0
(-2125 -9400);
DISPLAY 0.723404 (-2125 -9400);
PAINT GREEN (-2125 -9400);
DISPLAY INVISIBLE (-2125 -9400);
FORCEPROP 1 LAST PATH I257
J 0
(-1750 -9270);
DISPLAY 0.723404 (-1750 -9270);
PAINT GREEN (-1750 -9270);
DISPLAY INVISIBLE (-1750 -9270);
FORCEADD Q_CAP..1
(-2375 -8550);
FORCEPROP 1 LAST LOCATION PC6577_2
J 0
(-2325 -8450);
DISPLAY 0.978723 (-2325 -8450);
FORCEPROP 0 LAST $SEC 1
J 0
(-2325 -8400);
DISPLAY 0.680851 (-2325 -8400);
PAINT MONO (-2325 -8400);
DISPLAY INVISIBLE (-2325 -8400);
FORCEPROP 0 LAST CDS_SEC 1
J 0
(-2325 -8400);
DISPLAY 0.680851 (-2325 -8400);
DISPLAY INVISIBLE (-2325 -8400);
FORCEPROP 1 LASTPIN (-2375 -8450) $PN 1
J 0
(-2365 -8470);
DISPLAY 0.787234 (-2365 -8470);
PAINT MONO (-2365 -8470);
FORCEPROP 1 LASTPIN (-2375 -8650) $PN 2
J 0
(-2365 -8670);
DISPLAY 0.787234 (-2365 -8670);
PAINT MONO (-2365 -8670);
FORCEPROP 1 LAST VALUE 1UF
J 0
(-2325 -8500);
DISPLAY 0.617021 (-2325 -8500);
FORCEPROP 1 LAST TOLERANCE 10%
J 0
(-2325 -8600);
DISPLAY 0.617021 (-2325 -8600);
FORCEPROP 1 LAST MATERIAL X6S
J 0
(-2325 -8650);
DISPLAY 0.617021 (-2325 -8650);
FORCEPROP 1 LAST VOLTAGE 25V
J 0
(-2325 -8550);
DISPLAY 0.617021 (-2325 -8550);
FORCEPROP 1 LAST PACK_TYPE C0402
J 0
(-2325 -8750);
DISPLAY 0.617021 (-2325 -8750);
FORCEPROP 2 LAST CDS_LIB pure_quanta
J 0
(-2375 -8550);
DISPLAY INVISIBLE (-2375 -8550);
FORCEPROP 2 LAST BOM_COST VR_DIMM 
J 0
(-2325 -8400);
DISPLAY 0.680851 (-2325 -8400);
DISPLAY INVISIBLE (-2325 -8400);
FORCEPROP 1 LAST PART_NUMBER CH5104KEB02
J 0
(-2325 -8700);
DISPLAY 0.617021 (-2325 -8700);
DISPLAY INVISIBLE (-2325 -8700);
FORCEPROP 1 LAST PATH I258
J 0
(-2325 -8400);
DISPLAY 0.978723 (-2325 -8400);
PAINT WHITE (-2325 -8400);
DISPLAY INVISIBLE (-2325 -8400);
FORCEADD Q_CAP..1
(-2875 -8550);
FORCEPROP 1 LAST LOCATION PC6578_2
J 0
(-2825 -8450);
DISPLAY 0.978723 (-2825 -8450);
FORCEPROP 0 LAST $SEC 1
J 0
(-2825 -8400);
DISPLAY 0.680851 (-2825 -8400);
PAINT MONO (-2825 -8400);
DISPLAY INVISIBLE (-2825 -8400);
FORCEPROP 0 LAST CDS_SEC 1
J 0
(-2825 -8400);
DISPLAY 0.680851 (-2825 -8400);
DISPLAY INVISIBLE (-2825 -8400);
FORCEPROP 1 LASTPIN (-2875 -8450) $PN 1
J 0
(-2865 -8470);
DISPLAY 0.787234 (-2865 -8470);
PAINT MONO (-2865 -8470);
FORCEPROP 1 LASTPIN (-2875 -8650) $PN 2
J 0
(-2865 -8670);
DISPLAY 0.787234 (-2865 -8670);
PAINT MONO (-2865 -8670);
FORCEPROP 1 LAST TOLERANCE 10%
J 0
(-2825 -8600);
DISPLAY 0.617021 (-2825 -8600);
FORCEPROP 1 LAST VALUE 3300PF
J 0
(-2825 -8500);
DISPLAY 0.617021 (-2825 -8500);
FORCEPROP 1 LAST VOLTAGE 50V
J 0
(-2825 -8550);
DISPLAY 0.617021 (-2825 -8550);
FORCEPROP 1 LAST MATERIAL X7R
J 0
(-2825 -8650);
DISPLAY 0.617021 (-2825 -8650);
FORCEPROP 1 LAST PACK_TYPE 0402
J 0
(-2825 -8750);
DISPLAY 0.617021 (-2825 -8750);
FORCEPROP 2 LAST CDS_LIB pure_quanta
J 0
(-2875 -8550);
DISPLAY INVISIBLE (-2875 -8550);
FORCEPROP 2 LAST BOM_COST VR_DIMM 
J 0
(-2825 -8400);
DISPLAY 0.680851 (-2825 -8400);
DISPLAY INVISIBLE (-2825 -8400);
FORCEPROP 1 LAST PART_NUMBER TMP_QCH2336K1B12
J 0
(-2825 -8700);
DISPLAY 0.617021 (-2825 -8700);
DISPLAY INVISIBLE (-2825 -8700);
FORCEPROP 1 LAST PATH I259
J 0
(-2825 -8400);
DISPLAY 0.978723 (-2825 -8400);
PAINT WHITE (-2825 -8400);
DISPLAY INVISIBLE (-2825 -8400);
FORCEADD UNIVERSAL_GND..1
(-2375 -8825);
FORCEPROP 3 LASTPIN (-2375 -8775) SIG_NAME GND\g
J 0
(-2365 -8765);
DISPLAY 0.659574 (-2365 -8765);
PAINT MONO (-2365 -8765);
DISPLAY INVISIBLE (-2365 -8765);
FORCEPROP 2 LAST CDS_LIB pure_quanta_power
J 0
(-2375 -8825);
DISPLAY INVISIBLE (-2375 -8825);
FORCEPROP 1 LAST HDL_POWER GND
J 1
(-2350 -8900);
DISPLAY 0.872340 (-2350 -8900);
PAINT GREEN (-2350 -8900);
DISPLAY INVISIBLE (-2350 -8900);
FORCEPROP 1 LAST PATH I260
J 0
(-2300 -8825);
DISPLAY 0.872340 (-2300 -8825);
PAINT AQUA (-2300 -8825);
DISPLAY INVISIBLE (-2300 -8825);
FORCEADD UNIVERSAL_GND..1
(-2875 -8825);
FORCEPROP 3 LASTPIN (-2875 -8775) SIG_NAME GND\g
J 0
(-2865 -8765);
DISPLAY 0.659574 (-2865 -8765);
PAINT MONO (-2865 -8765);
DISPLAY INVISIBLE (-2865 -8765);
FORCEPROP 2 LAST CDS_LIB pure_quanta_power
J 0
(-2875 -8825);
DISPLAY INVISIBLE (-2875 -8825);
FORCEPROP 1 LAST HDL_POWER GND
J 1
(-2850 -8900);
DISPLAY 0.872340 (-2850 -8900);
PAINT GREEN (-2850 -8900);
DISPLAY INVISIBLE (-2850 -8900);
FORCEPROP 1 LAST PATH I261
J 0
(-2800 -8825);
DISPLAY 0.872340 (-2800 -8825);
PAINT AQUA (-2800 -8825);
DISPLAY INVISIBLE (-2800 -8825);
FORCEADD Q_RES..1
(-2375 -9000);
FORCEPROP 1 LAST LOCATION PR6562
J 0
(-2600 -9000);
DISPLAY 0.638298 (-2600 -9000);
FORCEPROP 0 LAST $SEC 1
J 0
(-2250 -8850);
DISPLAY 0.680851 (-2250 -8850);
PAINT MONO (-2250 -8850);
DISPLAY INVISIBLE (-2250 -8850);
FORCEPROP 0 LAST CDS_SEC 1
J 0
(-2250 -8850);
DISPLAY 0.680851 (-2250 -8850);
DISPLAY INVISIBLE (-2250 -8850);
FORCEPROP 1 LASTPIN (-2475 -9000) $PN 1
J 0
(-2463 -8988);
DISPLAY 0.787234 (-2463 -8988);
PAINT MONO (-2463 -8988);
FORCEPROP 1 LASTPIN (-2275 -9000) $PN 2
J 0
(-2313 -8988);
DISPLAY 0.787234 (-2313 -8988);
PAINT MONO (-2313 -8988);
FORCEPROP 1 LAST MATERIAL CHIP
J 0
(-2525 -8875);
DISPLAY 0.510638 (-2525 -8875);
FORCEPROP 1 LAST PACK_TYPE 0402LF
J 0
(-2250 -8875);
DISPLAY 0.510638 (-2250 -8875);
FORCEPROP 1 LAST TOLERANCE 1%
J 0
(-2175 -9000);
DISPLAY 0.510638 (-2175 -9000);
FORCEPROP 1 LAST WATTAGE 1/16W
J 2
(-2275 -8875);
DISPLAY 0.510638 (-2275 -8875);
FORCEPROP 1 LAST VALUE 5.6
J 2
(-2200 -9000);
DISPLAY 0.510638 (-2200 -9000);
FORCEPROP 2 LAST CDS_LIB pure_quanta
J 0
(-2375 -9000);
DISPLAY INVISIBLE (-2375 -9000);
FORCEPROP 1 LAST PART_NUMBER CS-5602FB01
J 0
(-2525 -8925);
DISPLAY 0.510638 (-2525 -8925);
DISPLAY INVISIBLE (-2525 -8925);
FORCEPROP 1 LAST PATH I262
J 0
(-2425 -8850);
DISPLAY 0.978723 (-2425 -8850);
PAINT WHITE (-2425 -8850);
DISPLAY INVISIBLE (-2425 -8850);
FORCEADD Q_RES..1
(-1950 -10425);
FORCEPROP 1 LAST LOCATION PR6564
J 0
(-2075 -10500);
DISPLAY 0.978723 (-2075 -10500);
FORCEPROP 0 LAST $SEC 1
J 0
(-1800 -10250);
DISPLAY 0.680851 (-1800 -10250);
PAINT MONO (-1800 -10250);
DISPLAY INVISIBLE (-1800 -10250);
FORCEPROP 0 LAST CDS_SEC 1
J 0
(-1800 -10250);
DISPLAY 0.680851 (-1800 -10250);
DISPLAY INVISIBLE (-1800 -10250);
FORCEPROP 1 LASTPIN (-2050 -10425) $PN 1
J 0
(-2038 -10413);
DISPLAY 0.787234 (-2038 -10413);
PAINT MONO (-2038 -10413);
FORCEPROP 1 LASTPIN (-1850 -10425) $PN 2
J 0
(-1888 -10413);
DISPLAY 0.787234 (-1888 -10413);
PAINT MONO (-1888 -10413);
FORCEPROP 1 LAST MATERIAL CHIP
J 0
(-2150 -10300);
DISPLAY 0.617021 (-2150 -10300);
FORCEPROP 1 LAST WATTAGE 1/16W
J 2
(-1850 -10300);
DISPLAY 0.617021 (-1850 -10300);
FORCEPROP 1 LAST PACK_TYPE 0402LF
J 0
(-1800 -10300);
DISPLAY 0.617021 (-1800 -10300);
FORCEPROP 1 LAST VALUE 0
J 2
(-1775 -10425);
DISPLAY 0.617021 (-1775 -10425);
FORCEPROP 1 LAST TOLERANCE 5%
J 0
(-1725 -10425);
DISPLAY 0.617021 (-1725 -10425);
FORCEPROP 2 LAST BOM_COST VR_DIMM 
J 0
(-2000 -10450);
DISPLAY 0.680851 (-2000 -10450);
DISPLAY INVISIBLE (-2000 -10450);
FORCEPROP 2 LAST CDS_LIB pure_quanta
J 0
(-1950 -10425);
DISPLAY INVISIBLE (-1950 -10425);
FORCEPROP 1 LAST PART_NUMBER CS00002JB13
J 0
(-2150 -10350);
DISPLAY 0.617021 (-2150 -10350);
DISPLAY INVISIBLE (-2150 -10350);
FORCEPROP 1 LAST PATH I263
J 0
(-2000 -10275);
DISPLAY 0.978723 (-2000 -10275);
PAINT WHITE (-2000 -10275);
DISPLAY INVISIBLE (-2000 -10275);
FORCEADD UNIVERSAL_GND..1
(-3400 -10150);
FORCEPROP 3 LASTPIN (-3400 -10100) SIG_NAME GND\g
J 0
(-3390 -10090);
DISPLAY 0.659574 (-3390 -10090);
PAINT MONO (-3390 -10090);
DISPLAY INVISIBLE (-3390 -10090);
FORCEPROP 2 LAST CDS_LIB pure_quanta_power
J 0
(-3400 -10150);
DISPLAY INVISIBLE (-3400 -10150);
FORCEPROP 1 LAST HDL_POWER GND
J 1
(-3375 -10225);
DISPLAY 0.872340 (-3375 -10225);
PAINT GREEN (-3375 -10225);
DISPLAY INVISIBLE (-3375 -10225);
FORCEPROP 1 LAST PATH I264
J 0
(-3325 -10150);
DISPLAY 0.872340 (-3325 -10150);
PAINT AQUA (-3325 -10150);
DISPLAY INVISIBLE (-3325 -10150);
FORCEADD UNIVERSAL_POWER..1
(-5775 -7750);
FORCEPROP 3 LASTPIN (-5775 -7800) SIG_NAME P0V9_RETIMER_CPU0_PVCC\g
J 0
(-5765 -7790);
DISPLAY 0.659574 (-5765 -7790);
PAINT MONO (-5765 -7790);
DISPLAY INVISIBLE (-5765 -7790);
FORCEPROP 1 LAST HDL_POWER P0V9_RETIMER_CPU0_PVCC
J 1
(-5775 -7700);
DISPLAY 0.872340 (-5775 -7700);
PAINT GREEN (-5775 -7700);
FORCEPROP 2 LAST CDS_LIB pure_quanta_power
J 0
(-5775 -7750);
DISPLAY INVISIBLE (-5775 -7750);
FORCEPROP 1 LAST PATH I265
J 0
(-5725 -7725);
DISPLAY 0.872340 (-5725 -7725);
PAINT AQUA (-5725 -7725);
DISPLAY INVISIBLE (-5725 -7725);
FORCEADD Q_CAP..1
(-5075 -8400);
FORCEPROP 1 LAST LOCATION PC6551_09P0_2
J 0
(-5025 -8300);
DISPLAY 0.978723 (-5025 -8300);
FORCEPROP 0 LAST $SEC 1
J 0
(-5025 -8250);
DISPLAY 0.680851 (-5025 -8250);
PAINT MONO (-5025 -8250);
DISPLAY INVISIBLE (-5025 -8250);
FORCEPROP 0 LAST CDS_SEC 1
J 0
(-5025 -8250);
DISPLAY 0.680851 (-5025 -8250);
DISPLAY INVISIBLE (-5025 -8250);
FORCEPROP 1 LASTPIN (-5075 -8300) $PN 1
J 0
(-5065 -8320);
DISPLAY 0.787234 (-5065 -8320);
PAINT MONO (-5065 -8320);
FORCEPROP 1 LASTPIN (-5075 -8500) $PN 2
J 0
(-5065 -8520);
DISPLAY 0.787234 (-5065 -8520);
PAINT MONO (-5065 -8520);
FORCEPROP 1 LAST VALUE 2.2UF
J 0
(-5025 -8350);
DISPLAY 0.617021 (-5025 -8350);
FORCEPROP 1 LAST VOLTAGE 10V
J 0
(-5025 -8400);
DISPLAY 0.617021 (-5025 -8400);
FORCEPROP 1 LAST TOLERANCE 10%
J 0
(-5025 -8450);
DISPLAY 0.617021 (-5025 -8450);
FORCEPROP 1 LAST MATERIAL X6S
J 0
(-5025 -8500);
DISPLAY 0.617021 (-5025 -8500);
FORCEPROP 1 LAST PACK_TYPE C0402
J 0
(-5025 -8600);
DISPLAY 0.617021 (-5025 -8600);
FORCEPROP 2 LAST CDS_LIB pure_quanta
J 0
(-5075 -8400);
DISPLAY INVISIBLE (-5075 -8400);
FORCEPROP 2 LAST BOM_COST VR_DIMM 
J 0
(-5025 -8250);
DISPLAY 0.680851 (-5025 -8250);
DISPLAY INVISIBLE (-5025 -8250);
FORCEPROP 1 LAST PART_NUMBER CH5222KEB01
J 0
(-5025 -8550);
DISPLAY 0.617021 (-5025 -8550);
DISPLAY INVISIBLE (-5025 -8550);
FORCEPROP 1 LAST PATH I267
J 0
(-5025 -8250);
DISPLAY 0.978723 (-5025 -8250);
PAINT WHITE (-5025 -8250);
DISPLAY INVISIBLE (-5025 -8250);
FORCEADD UNIVERSAL_GND..1
(-5075 -8650);
FORCEPROP 3 LASTPIN (-5075 -8600) SIG_NAME GND\g
J 0
(-5065 -8590);
DISPLAY 0.659574 (-5065 -8590);
PAINT MONO (-5065 -8590);
DISPLAY INVISIBLE (-5065 -8590);
FORCEPROP 2 LAST CDS_LIB pure_quanta_power
J 0
(-5075 -8650);
DISPLAY INVISIBLE (-5075 -8650);
FORCEPROP 1 LAST HDL_POWER GND
J 1
(-5050 -8725);
DISPLAY 0.872340 (-5050 -8725);
PAINT GREEN (-5050 -8725);
DISPLAY INVISIBLE (-5050 -8725);
FORCEPROP 1 LAST PATH I268
J 0
(-5000 -8650);
DISPLAY 0.872340 (-5000 -8650);
PAINT AQUA (-5000 -8650);
DISPLAY INVISIBLE (-5000 -8650);
FORCEADD Q_RES..2
(-5775 -8400);
FORCEPROP 1 LAST LOCATION PR6560
J 0
(-5730 -8275);
DISPLAY 0.723404 (-5730 -8275);
FORCEPROP 0 LAST $SEC 1
J 0
(-5725 -8225);
DISPLAY 0.680851 (-5725 -8225);
PAINT MONO (-5725 -8225);
DISPLAY INVISIBLE (-5725 -8225);
FORCEPROP 0 LAST CDS_SEC 1
J 0
(-5725 -8225);
DISPLAY 0.680851 (-5725 -8225);
DISPLAY INVISIBLE (-5725 -8225);
FORCEPROP 1 LASTPIN (-5775 -8300) $PN 1
J 0
(-5770 -8338);
DISPLAY 0.787234 (-5770 -8338);
PAINT MONO (-5770 -8338);
FORCEPROP 1 LASTPIN (-5775 -8500) $PN 2
J 0
(-5770 -8490);
DISPLAY 0.787234 (-5770 -8490);
PAINT MONO (-5770 -8490);
FORCEPROP 1 LAST PACK_TYPE 0402LF
J 0
(-5735 -8575);
DISPLAY 0.617021 (-5735 -8575);
FORCEPROP 1 LAST WATTAGE 1/16W
J 0
(-5735 -8425);
DISPLAY 0.617021 (-5735 -8425);
FORCEPROP 1 LAST MATERIAL CHIP
J 0
(-5735 -8475);
DISPLAY 0.617021 (-5735 -8475);
FORCEPROP 1 LAST TOLERANCE 5%
J 0
(-5730 -8375);
DISPLAY 0.617021 (-5730 -8375);
FORCEPROP 1 LAST VALUE 2.2
J 0
(-5730 -8325);
DISPLAY 0.617021 (-5730 -8325);
FORCEPROP 2 LAST BOM_COST VR_DIMM 
J 0
(-5725 -8225);
DISPLAY 0.680851 (-5725 -8225);
DISPLAY INVISIBLE (-5725 -8225);
FORCEPROP 2 LAST CDS_LIB pure_quanta
J 0
(-5775 -8400);
DISPLAY INVISIBLE (-5775 -8400);
FORCEPROP 1 LAST PART_NUMBER TMP_QCS-2202JB25
J 0
(-5750 -8525);
DISPLAY 0.617021 (-5750 -8525);
DISPLAY INVISIBLE (-5750 -8525);
FORCEPROP 1 LAST PATH I269
J 0
(-5725 -8225);
DISPLAY 0.978723 (-5725 -8225);
PAINT WHITE (-5725 -8225);
DISPLAY INVISIBLE (-5725 -8225);
FORCEADD Q_CAP..1
(-2000 -5650);
FORCEPROP 1 LAST LOCATION PC6556_1
J 0
(-1950 -5550);
DISPLAY 0.787234 (-1950 -5550);
FORCEPROP 0 LAST $SEC 1
J 0
(-1950 -5500);
DISPLAY 0.680851 (-1950 -5500);
PAINT MONO (-1950 -5500);
DISPLAY INVISIBLE (-1950 -5500);
FORCEPROP 0 LAST CDS_SEC 1
J 0
(-1925 -5425);
DISPLAY 0.680851 (-1925 -5425);
PAINT MONO (-1925 -5425);
DISPLAY INVISIBLE (-1925 -5425);
FORCEPROP 1 LASTPIN (-2000 -5550) $PN 1
J 0
(-1990 -5570);
DISPLAY 0.787234 (-1990 -5570);
PAINT MONO (-1990 -5570);
FORCEPROP 1 LASTPIN (-2000 -5750) $PN 2
J 0
(-1990 -5770);
DISPLAY 0.787234 (-1990 -5770);
PAINT MONO (-1990 -5770);
FORCEPROP 1 LAST VOLTAGE 16V
J 0
(-1950 -5650);
DISPLAY 0.638298 (-1950 -5650);
FORCEPROP 1 LAST MATERIAL X6S
J 0
(-1950 -5750);
DISPLAY 0.638298 (-1950 -5750);
FORCEPROP 1 LAST TOLERANCE 20%
J 0
(-1950 -5700);
DISPLAY 0.638298 (-1950 -5700);
FORCEPROP 1 LAST PACK_TYPE C0805
J 0
(-1950 -5850);
DISPLAY 0.638298 (-1950 -5850);
FORCEPROP 1 LAST VALUE 22UF
J 0
(-1950 -5600);
DISPLAY 0.638298 (-1950 -5600);
FORCEPROP 2 LAST CDS_LIB pure_quanta
J 0
(-2000 -5650);
DISPLAY INVISIBLE (-2000 -5650);
FORCEPROP 2 LAST BOM_COST VR_DIMM 
J 0
(-1950 -5500);
DISPLAY 0.680851 (-1950 -5500);
DISPLAY INVISIBLE (-1950 -5500);
FORCEPROP 0 LAST REUSE_ID 41
J 0
(-1950 -5450);
DISPLAY 0.680851 (-1950 -5450);
DISPLAY INVISIBLE (-1950 -5450);
FORCEPROP 1 LAST PART_NUMBER CH6223MEA01
J 0
(-1950 -5800);
DISPLAY 0.638298 (-1950 -5800);
DISPLAY INVISIBLE (-1950 -5800);
FORCEPROP 1 LAST PATH I27
J 0
(-1950 -5500);
DISPLAY 0.978723 (-1950 -5500);
PAINT WHITE (-1950 -5500);
DISPLAY INVISIBLE (-1950 -5500);
FORCEADD ISL99390FRZTR5935..1
(-3975 -9350);
FORCEPROP 1 LAST LOCATION PU6504
J 0
(-4275 -8475);
DISPLAY 0.723404 (-4275 -8475);
PAINT GREEN (-4275 -8475);
FORCEPROP 2 LAST SEC 1
J 0
(-4275 -8250);
DISPLAY 0.680851 (-4275 -8250);
PAINT MONO (-4275 -8250);
DISPLAY INVISIBLE (-4275 -8250);
FORCEPROP 2 LASTPIN (-3575 -9800) $PN 2
J 0
(-3565 -9790);
DISPLAY 0.680851 (-3565 -9790);
PAINT MONO (-3565 -9790);
FORCEPROP 2 LASTPIN (-3575 -9000) $PN 33
J 0
(-3565 -8990);
DISPLAY 0.680851 (-3565 -8990);
PAINT MONO (-3565 -8990);
FORCEPROP 2 LASTPIN (-4425 -9600) $PN 31
J 2
(-4435 -9590);
DISPLAY 0.680851 (-4435 -9590);
PAINT MONO (-4435 -9590);
FORCEPROP 2 LASTPIN (-4425 -9200) $PN 35
J 2
(-4435 -9190);
DISPLAY 0.680851 (-4435 -9190);
PAINT MONO (-4435 -9190);
FORCEPROP 2 LASTPIN (-3575 -9650) $PN 6
J 0
(-3565 -9640);
DISPLAY 0.680851 (-3565 -9640);
PAINT MONO (-3565 -9640);
FORCEPROP 2 LASTPIN (-3575 -9700) $PN 41
J 0
(-3565 -9690);
DISPLAY 0.680851 (-3565 -9690);
PAINT MONO (-3565 -9690);
FORCEPROP 2 LASTPIN (-4425 -9350) $PN 38
J 2
(-4435 -9340);
DISPLAY 0.680851 (-4435 -9340);
PAINT MONO (-4435 -9340);
FORCEPROP 2 LASTPIN (-4425 -9650) $PN 37
J 2
(-4435 -9640);
DISPLAY 0.680851 (-4435 -9640);
PAINT MONO (-4435 -9640);
FORCEPROP 2 LASTPIN (-3575 -9850) $PN 5
J 0
(-3565 -9840);
DISPLAY 0.680851 (-3565 -9840);
PAINT MONO (-3565 -9840);
FORCEPROP 2 LASTPIN (-3575 -9900) $PN 7_9-20_24
J 0
(-3565 -9890);
DISPLAY 0.680851 (-3565 -9890);
PAINT MONO (-3565 -9890);
FORCEPROP 2 LASTPIN (-3575 -9950) $PN 40
J 0
(-3565 -9940);
DISPLAY 0.680851 (-3565 -9940);
PAINT MONO (-3565 -9940);
FORCEPROP 2 LASTPIN (-3575 -9250) $PN 32
J 0
(-3565 -9240);
DISPLAY 0.680851 (-3565 -9240);
PAINT MONO (-3565 -9240);
FORCEPROP 2 LASTPIN (-4425 -8700) $PN 4
J 2
(-4435 -8690);
DISPLAY 0.680851 (-4435 -8690);
PAINT MONO (-4435 -8690);
FORCEPROP 2 LASTPIN (-4425 -9950) $PN 34
J 2
(-4435 -9940);
DISPLAY 0.680851 (-4435 -9940);
PAINT MONO (-4435 -9940);
FORCEPROP 2 LASTPIN (-4425 -9450) $PN 39
J 2
(-4435 -9440);
DISPLAY 0.680851 (-4435 -9440);
PAINT MONO (-4435 -9440);
FORCEPROP 2 LASTPIN (-3575 -9350) $PN 10_19
J 0
(-3565 -9340);
DISPLAY 0.680851 (-3565 -9340);
PAINT MONO (-3565 -9340);
FORCEPROP 2 LASTPIN (-4425 -9850) $PN 36
J 2
(-4435 -9840);
DISPLAY 0.680851 (-4435 -9840);
PAINT MONO (-4435 -9840);
FORCEPROP 2 LASTPIN (-4425 -9000) $PN 3
J 2
(-4435 -8990);
DISPLAY 0.680851 (-4435 -8990);
PAINT MONO (-4435 -8990);
FORCEPROP 2 LASTPIN (-3575 -8700) $PN 25_29
J 0
(-3565 -8690);
DISPLAY 0.680851 (-3565 -8690);
PAINT MONO (-3565 -8690);
FORCEPROP 2 LASTPIN (-3575 -8750) $PN 30
J 0
(-3565 -8740);
DISPLAY 0.680851 (-3565 -8740);
PAINT MONO (-3565 -8740);
FORCEPROP 2 LASTPIN (-3575 -9600) $PN 1
J 0
(-3565 -9590);
DISPLAY 0.680851 (-3565 -9590);
PAINT MONO (-3565 -9590);
FORCEPROP 2 LAST VALUE ISL99390FRZ-TR5935
J 0
(-4275 -8375);
DISPLAY 0.617021 (-4275 -8375);
FORCEPROP 1 LAST MATERIAL IC
J 0
(-4275 -8625);
DISPLAY 0.723404 (-4275 -8625);
PAINT GREEN (-4275 -8625);
FORCEPROP 2 LAST PART_TYPE SMLF
J 0
(-4275 -8300);
DISPLAY 0.680851 (-4275 -8300);
FORCEPROP 1 LAST CDS_LMAN_SYM_OUTLINE -300,700,250,-650
J 0
(-3975 -9350);
DISPLAY 0.468085 (-3975 -9350);
PAINT GREEN (-3975 -9350);
DISPLAY INVISIBLE (-3975 -9350);
FORCEPROP 2 LAST CDS_LIB pure_quanta
J 0
(-3975 -9350);
DISPLAY INVISIBLE (-3975 -9350);
FORCEPROP 2 LAST SEC_TYPE 
J 0
(-4275 -8250);
DISPLAY 0.680851 (-4275 -8250);
DISPLAY INVISIBLE (-4275 -8250);
FORCEPROP 2 LAST BOM_COST VR_DIMM 
J 0
(-4250 -8325);
DISPLAY 0.680851 (-4250 -8325);
DISPLAY INVISIBLE (-4250 -8325);
FORCEPROP 1 LAST NEEDS_NO_SIZE TRUE
J 0
(-3975 -9350);
DISPLAY 0.723404 (-3975 -9350);
PAINT GREEN (-3975 -9350);
DISPLAY INVISIBLE (-3975 -9350);
FORCEPROP 1 LAST PART_NUMBER AL099390004
J 0
(-4275 -8550);
DISPLAY 0.723404 (-4275 -8550);
PAINT GREEN (-4275 -8550);
DISPLAY INVISIBLE (-4275 -8550);
FORCEPROP 1 LAST PATH I270
J 0
(-3975 -9350);
DISPLAY 0.723404 (-3975 -9350);
PAINT GREEN (-3975 -9350);
DISPLAY INVISIBLE (-3975 -9350);
FORCEADD Q_CAP..1
(-5775 -8925);
FORCEPROP 1 LAST LOCATION PC6575
J 0
(-5725 -8825);
DISPLAY 0.978723 (-5725 -8825);
FORCEPROP 0 LAST $SEC 1
J 0
(-5725 -8775);
DISPLAY 0.680851 (-5725 -8775);
PAINT MONO (-5725 -8775);
DISPLAY INVISIBLE (-5725 -8775);
FORCEPROP 0 LAST CDS_SEC 1
J 0
(-5725 -8775);
DISPLAY 0.680851 (-5725 -8775);
DISPLAY INVISIBLE (-5725 -8775);
FORCEPROP 1 LASTPIN (-5775 -8825) $PN 1
J 0
(-5765 -8845);
DISPLAY 0.787234 (-5765 -8845);
PAINT MONO (-5765 -8845);
FORCEPROP 1 LASTPIN (-5775 -9025) $PN 2
J 0
(-5765 -9045);
DISPLAY 0.787234 (-5765 -9045);
PAINT MONO (-5765 -9045);
FORCEPROP 1 LAST VALUE 2.2UF
J 0
(-5725 -8875);
DISPLAY 0.617021 (-5725 -8875);
FORCEPROP 1 LAST VOLTAGE 10V
J 0
(-5725 -8925);
DISPLAY 0.617021 (-5725 -8925);
FORCEPROP 1 LAST MATERIAL X6S
J 0
(-5725 -8975);
DISPLAY 0.617021 (-5725 -8975);
FORCEPROP 1 LAST PACK_TYPE C0402
J 0
(-5725 -9075);
DISPLAY 0.617021 (-5725 -9075);
FORCEPROP 2 LAST CDS_LIB pure_quanta
J 0
(-5775 -8925);
DISPLAY INVISIBLE (-5775 -8925);
FORCEPROP 2 LAST BOM_COST VR_DIMM 
J 0
(-5725 -8775);
DISPLAY 0.680851 (-5725 -8775);
DISPLAY INVISIBLE (-5725 -8775);
FORCEPROP 1 LAST TOLERANCE 10%
J 0
(-5725 -8975);
DISPLAY 0.978723 (-5725 -8975);
PAINT SKYBLUE (-5725 -8975);
DISPLAY INVISIBLE (-5725 -8975);
FORCEPROP 1 LAST PART_NUMBER CH5222KEB01
J 0
(-5725 -9025);
DISPLAY 0.617021 (-5725 -9025);
DISPLAY INVISIBLE (-5725 -9025);
FORCEPROP 1 LAST PATH I271
J 0
(-5725 -8775);
DISPLAY 0.978723 (-5725 -8775);
PAINT WHITE (-5725 -8775);
DISPLAY INVISIBLE (-5725 -8775);
FORCEADD UNIVERSAL_GND..1
(-5775 -9125);
FORCEPROP 3 LASTPIN (-5775 -9075) SIG_NAME GND\g
J 0
(-5765 -9065);
DISPLAY 0.659574 (-5765 -9065);
PAINT MONO (-5765 -9065);
DISPLAY INVISIBLE (-5765 -9065);
FORCEPROP 2 LAST CDS_LIB pure_quanta_power
J 0
(-5775 -9125);
DISPLAY INVISIBLE (-5775 -9125);
FORCEPROP 1 LAST HDL_POWER GND
J 1
(-5750 -9200);
DISPLAY 0.872340 (-5750 -9200);
PAINT GREEN (-5750 -9200);
DISPLAY INVISIBLE (-5750 -9200);
FORCEPROP 1 LAST PATH I272
J 0
(-5700 -9125);
DISPLAY 0.872340 (-5700 -9125);
PAINT AQUA (-5700 -9125);
DISPLAY INVISIBLE (-5700 -9125);
FORCEADD OFFPAGE..4
R 2
(-5806 -9450);
FORCEPROP 2 LAST $XR1 364 
J 0
(-6178 -9450);
DISPLAY 0.638298 (-6178 -9450);
PAINT MONO (-6178 -9450);
FORCEPROP 2 LAST $XR0 363 
J 0
(-6058 -9450);
DISPLAY 0.638298 (-6058 -9450);
PAINT MONO (-6058 -9450);
FORCEPROP 2 LAST CDS_LIB standard
J 0
(-5806 -9450);
DISPLAY INVISIBLE (-5806 -9450);
FORCEPROP 2 LAST BOM_COST VR_DIMM 
J 0
(-6081 -9400);
DISPLAY 0.680851 (-6081 -9400);
DISPLAY INVISIBLE (-6081 -9400);
FORCEPROP 1 LAST OFFPAGE TRUE
J 2
(-6131 -9575);
DISPLAY 0.872340 (-6131 -9575);
PAINT GREEN (-6131 -9575);
DISPLAY INVISIBLE (-6131 -9575);
FORCEPROP 1 LAST COMMENT_BODY TRUE
J 2
(-5781 -9550);
DISPLAY 0.872340 (-5781 -9550);
PAINT GREEN (-5781 -9550);
DISPLAY INVISIBLE (-5781 -9550);
FORCEPROP 2 LAST PATH I273
J 0
(-5750 -9375);
DISPLAY 0.680851 (-5750 -9375);
DISPLAY INVISIBLE (-5750 -9375);
FORCEADD OFFPAGE..2
R 2
(-5275 -9850);
FORCEPROP 2 LAST $XR1 363 
J 0
(-5530 -9886);
DISPLAY 0.638298 (-5530 -9886);
PAINT MONO (-5530 -9886);
FORCEPROP 2 LAST $XR0 364 
J 0
(-5530 -9850);
DISPLAY 0.638298 (-5530 -9850);
PAINT MONO (-5530 -9850);
FORCEPROP 2 LAST CDS_LIB standard
J 0
(-5275 -9850);
DISPLAY INVISIBLE (-5275 -9850);
FORCEPROP 2 LAST BOM_COST VR_DIMM 
J 0
(-5556 -9800);
DISPLAY 0.680851 (-5556 -9800);
DISPLAY INVISIBLE (-5556 -9800);
FORCEPROP 1 LAST OFFPAGE TRUE
J 2
(-5600 -9975);
DISPLAY 1.170213 (-5600 -9975);
PAINT GREEN (-5600 -9975);
DISPLAY INVISIBLE (-5600 -9975);
FORCEPROP 1 LAST COMMENT_BODY TRUE
J 2
(-5230 -9945);
DISPLAY 1.170213 (-5230 -9945);
PAINT GREEN (-5230 -9945);
DISPLAY INVISIBLE (-5230 -9945);
FORCEPROP 2 LAST PATH I274
J 0
(-5225 -9775);
DISPLAY 0.680851 (-5225 -9775);
DISPLAY INVISIBLE (-5225 -9775);
FORCEADD OFFPAGE..4
R 2
(-5250 -9950);
FORCEPROP 2 LAST $XR0 363 
J 0
(-5502 -9950);
DISPLAY 0.638298 (-5502 -9950);
PAINT MONO (-5502 -9950);
FORCEPROP 2 LAST CDS_LIB standard
J 0
(-5250 -9950);
DISPLAY INVISIBLE (-5250 -9950);
FORCEPROP 2 LAST BOM_COST VR_DIMM 
J 0
(-5545 -9900);
DISPLAY 0.680851 (-5545 -9900);
DISPLAY INVISIBLE (-5545 -9900);
FORCEPROP 1 LAST OFFPAGE TRUE
J 2
(-5575 -10075);
DISPLAY 0.872340 (-5575 -10075);
PAINT GREEN (-5575 -10075);
DISPLAY INVISIBLE (-5575 -10075);
FORCEPROP 1 LAST COMMENT_BODY TRUE
J 2
(-5225 -10050);
DISPLAY 0.872340 (-5225 -10050);
PAINT GREEN (-5225 -10050);
DISPLAY INVISIBLE (-5225 -10050);
FORCEPROP 2 LAST PATH I275
J 0
(-5200 -9875);
DISPLAY 0.680851 (-5200 -9875);
DISPLAY INVISIBLE (-5200 -9875);
FORCEADD Q_RES..2
(-5725 -9900);
FORCEPROP 1 LAST LOCATION PR6561
J 0
(-5680 -9775);
DISPLAY 0.978723 (-5680 -9775);
FORCEPROP 0 LAST $SEC 1
J 0
(-5675 -9725);
DISPLAY 0.680851 (-5675 -9725);
PAINT MONO (-5675 -9725);
DISPLAY INVISIBLE (-5675 -9725);
FORCEPROP 0 LAST CDS_SEC 1
J 0
(-5675 -9725);
DISPLAY 0.680851 (-5675 -9725);
DISPLAY INVISIBLE (-5675 -9725);
FORCEPROP 1 LASTPIN (-5725 -9800) $PN 1
J 0
(-5720 -9838);
DISPLAY 0.787234 (-5720 -9838);
PAINT MONO (-5720 -9838);
FORCEPROP 1 LASTPIN (-5725 -10000) $PN 2
J 0
(-5720 -9990);
DISPLAY 0.787234 (-5720 -9990);
PAINT MONO (-5720 -9990);
FORCEPROP 1 LAST TOLERANCE 1%
J 0
(-5680 -9875);
DISPLAY 0.510638 (-5680 -9875);
FORCEPROP 1 LAST PACK_TYPE 0402LF
J 0
(-5685 -10075);
DISPLAY 0.510638 (-5685 -10075);
FORCEPROP 1 LAST VALUE 8.87K
J 0
(-5680 -9825);
DISPLAY 0.510638 (-5680 -9825);
FORCEPROP 1 LAST WATTAGE 1/16W
J 0
(-5685 -9925);
DISPLAY 0.510638 (-5685 -9925);
FORCEPROP 1 LAST MATERIAL EMPTY
J 0
(-5685 -9975);
DISPLAY 0.510638 (-5685 -9975);
FORCEPROP 2 LAST CDS_LIB pure_quanta
J 0
(-5725 -9900);
DISPLAY INVISIBLE (-5725 -9900);
FORCEPROP 1 LAST PART_NUMBER CS28872FB01
J 0
(-5685 -10025);
DISPLAY 0.510638 (-5685 -10025);
DISPLAY INVISIBLE (-5685 -10025);
FORCEPROP 1 LAST PATH I276
J 0
(-5675 -9725);
DISPLAY 0.978723 (-5675 -9725);
PAINT WHITE (-5675 -9725);
DISPLAY INVISIBLE (-5675 -9725);
FORCEADD UNIVERSAL_GND..1
(-5725 -10150);
FORCEPROP 3 LASTPIN (-5725 -10100) SIG_NAME GND\g
J 0
(-5715 -10090);
DISPLAY 0.659574 (-5715 -10090);
PAINT MONO (-5715 -10090);
DISPLAY INVISIBLE (-5715 -10090);
FORCEPROP 2 LAST CDS_LIB pure_quanta_power
J 0
(-5725 -10150);
DISPLAY INVISIBLE (-5725 -10150);
FORCEPROP 1 LAST HDL_POWER GND
J 1
(-5700 -10225);
DISPLAY 0.872340 (-5700 -10225);
PAINT GREEN (-5700 -10225);
DISPLAY INVISIBLE (-5700 -10225);
FORCEPROP 1 LAST PATH I277
J 0
(-5650 -10150);
DISPLAY 0.872340 (-5650 -10150);
PAINT AQUA (-5650 -10150);
DISPLAY INVISIBLE (-5650 -10150);
FORCEADD OFFPAGE..2
R 2
(-6325 -9350);
FORCEPROP 2 LAST $XR0 363 
J 0
(-6580 -9350);
DISPLAY 0.638298 (-6580 -9350);
PAINT MONO (-6580 -9350);
FORCEPROP 2 LAST CDS_LIB standard
J 0
(-6325 -9350);
DISPLAY INVISIBLE (-6325 -9350);
FORCEPROP 2 LAST BOM_COST VR_DIMM 
J 0
(-6606 -9300);
DISPLAY 0.680851 (-6606 -9300);
DISPLAY INVISIBLE (-6606 -9300);
FORCEPROP 1 LAST OFFPAGE TRUE
J 2
(-6650 -9475);
DISPLAY 1.170213 (-6650 -9475);
PAINT GREEN (-6650 -9475);
DISPLAY INVISIBLE (-6650 -9475);
FORCEPROP 1 LAST COMMENT_BODY TRUE
J 2
(-6280 -9445);
DISPLAY 1.170213 (-6280 -9445);
PAINT GREEN (-6280 -9445);
DISPLAY INVISIBLE (-6280 -9445);
FORCEPROP 2 LAST PATH I280
J 0
(-6275 -9275);
DISPLAY 0.680851 (-6275 -9275);
DISPLAY INVISIBLE (-6275 -9275);
FORCEADD Q_CAP..1
(-6525 -9775);
FORCEPROP 1 LAST LOCATION PC6576
J 0
(-6475 -9675);
DISPLAY 0.978723 (-6475 -9675);
FORCEPROP 0 LAST $SEC 1
J 0
(-6475 -9625);
DISPLAY 0.680851 (-6475 -9625);
PAINT MONO (-6475 -9625);
DISPLAY INVISIBLE (-6475 -9625);
FORCEPROP 0 LAST CDS_SEC 1
J 0
(-6475 -9625);
DISPLAY 0.680851 (-6475 -9625);
DISPLAY INVISIBLE (-6475 -9625);
FORCEPROP 1 LASTPIN (-6525 -9675) $PN 1
J 0
(-6515 -9695);
DISPLAY 0.787234 (-6515 -9695);
PAINT MONO (-6515 -9695);
FORCEPROP 1 LASTPIN (-6525 -9875) $PN 2
J 0
(-6515 -9895);
DISPLAY 0.787234 (-6515 -9895);
PAINT MONO (-6515 -9895);
FORCEPROP 1 LAST MATERIAL X7R
J 0
(-6475 -9875);
DISPLAY 0.617021 (-6475 -9875);
FORCEPROP 1 LAST VOLTAGE 50V
J 0
(-6475 -9775);
DISPLAY 0.617021 (-6475 -9775);
FORCEPROP 1 LAST TOLERANCE 10%
J 0
(-6475 -9825);
DISPLAY 0.617021 (-6475 -9825);
FORCEPROP 1 LAST PACK_TYPE C0402
J 0
(-6475 -9975);
DISPLAY 0.617021 (-6475 -9975);
FORCEPROP 1 LAST VALUE 100NF
J 0
(-6475 -9725);
DISPLAY 0.617021 (-6475 -9725);
FORCEPROP 2 LAST CDS_LIB pure_quanta
J 0
(-6525 -9775);
DISPLAY INVISIBLE (-6525 -9775);
FORCEPROP 2 LAST BOM_COST VR_CPU
J 0
(-6475 -9625);
DISPLAY 0.680851 (-6475 -9625);
DISPLAY INVISIBLE (-6475 -9625);
FORCEPROP 1 LAST PART_NUMBER CH4106K1B01
J 0
(-6475 -9925);
DISPLAY 0.617021 (-6475 -9925);
DISPLAY INVISIBLE (-6475 -9925);
FORCEPROP 1 LAST PATH I281
J 0
(-6475 -9625);
DISPLAY 0.978723 (-6475 -9625);
PAINT WHITE (-6475 -9625);
DISPLAY INVISIBLE (-6475 -9625);
FORCEADD UNIVERSAL_GND..1
(-6525 -9975);
FORCEPROP 3 LASTPIN (-6525 -9925) SIG_NAME GND\g
J 0
(-6515 -9915);
DISPLAY 0.659574 (-6515 -9915);
PAINT MONO (-6515 -9915);
DISPLAY INVISIBLE (-6515 -9915);
FORCEPROP 2 LAST CDS_LIB pure_quanta_power
J 0
(-6525 -9975);
DISPLAY INVISIBLE (-6525 -9975);
FORCEPROP 1 LAST HDL_POWER GND
J 1
(-6500 -10050);
DISPLAY 0.872340 (-6500 -10050);
PAINT GREEN (-6500 -10050);
DISPLAY INVISIBLE (-6500 -10050);
FORCEPROP 1 LAST PATH I282
J 0
(-6450 -9975);
DISPLAY 0.872340 (-6450 -9975);
PAINT AQUA (-6450 -9975);
DISPLAY INVISIBLE (-6450 -9975);
FORCEADD Q_RES..2
(-2400 -7175);
FORCEPROP 1 LAST LOCATION PR6555
J 0
(-2355 -7050);
DISPLAY 0.617021 (-2355 -7050);
PAINT SKYBLUE (-2355 -7050);
FORCEPROP 0 LAST $SEC 1
J 0
(-2350 -7000);
DISPLAY 0.680851 (-2350 -7000);
PAINT MONO (-2350 -7000);
DISPLAY INVISIBLE (-2350 -7000);
FORCEPROP 0 LAST CDS_SEC 1
J 0
(-2350 -7000);
DISPLAY 0.680851 (-2350 -7000);
DISPLAY INVISIBLE (-2350 -7000);
FORCEPROP 1 LASTPIN (-2400 -7075) $PN 1
J 0
(-2395 -7113);
DISPLAY 0.787234 (-2395 -7113);
PAINT MONO (-2395 -7113);
FORCEPROP 1 LASTPIN (-2400 -7275) $PN 2
J 0
(-2395 -7265);
DISPLAY 0.787234 (-2395 -7265);
PAINT MONO (-2395 -7265);
FORCEPROP 1 LAST PACK_TYPE 0402LF
J 0
(-2360 -7350);
DISPLAY 0.489362 (-2360 -7350);
PAINT SKYBLUE (-2360 -7350);
FORCEPROP 1 LAST WATTAGE 1/8W
J 0
(-2360 -7200);
DISPLAY 0.489362 (-2360 -7200);
PAINT SKYBLUE (-2360 -7200);
FORCEPROP 1 LAST MATERIAL EMPTY
J 0
(-2360 -7250);
DISPLAY 0.489362 (-2360 -7250);
PAINT RED (-2360 -7250);
FORCEPROP 1 LAST VALUE 1.5
J 0
(-2355 -7100);
DISPLAY 0.489362 (-2355 -7100);
PAINT SKYBLUE (-2355 -7100);
FORCEPROP 1 LAST TOLERANCE 1%
J 0
(-2355 -7150);
DISPLAY 0.489362 (-2355 -7150);
PAINT SKYBLUE (-2355 -7150);
FORCEPROP 2 LAST CDS_LIB pure_quanta
J 0
(-2400 -7175);
DISPLAY INVISIBLE (-2400 -7175);
FORCEPROP 1 LAST PART_NUMBER CS-1504FB00
J 0
(-2360 -7300);
DISPLAY 0.489362 (-2360 -7300);
PAINT SKYBLUE (-2360 -7300);
DISPLAY INVISIBLE (-2360 -7300);
FORCEPROP 1 LAST PATH I283
J 0
(-2350 -7000);
DISPLAY 0.978723 (-2350 -7000);
PAINT WHITE (-2350 -7000);
DISPLAY INVISIBLE (-2350 -7000);
FORCEADD UNIVERSAL_GND..1
(-2400 -7400);
FORCEPROP 3 LASTPIN (-2400 -7350) SIG_NAME GND\g
J 0
(-2390 -7340);
DISPLAY 0.659574 (-2390 -7340);
PAINT MONO (-2390 -7340);
DISPLAY INVISIBLE (-2390 -7340);
FORCEPROP 2 LAST CDS_LIB pure_quanta_power
J 0
(-2400 -7400);
DISPLAY INVISIBLE (-2400 -7400);
FORCEPROP 1 LAST HDL_POWER GND
J 1
(-2375 -7475);
DISPLAY 0.872340 (-2375 -7475);
PAINT GREEN (-2375 -7475);
DISPLAY INVISIBLE (-2375 -7475);
FORCEPROP 1 LAST PATH I284
J 0
(-2325 -7400);
DISPLAY 0.872340 (-2325 -7400);
PAINT AQUA (-2325 -7400);
DISPLAY INVISIBLE (-2325 -7400);
FORCEADD Q_CAP..1
(-2400 -6650);
FORCEPROP 1 LAST LOCATION PC6564
J 0
(-2350 -6550);
DISPLAY 0.617021 (-2350 -6550);
PAINT SKYBLUE (-2350 -6550);
FORCEPROP 0 LAST $SEC 1
J 0
(-2350 -6500);
DISPLAY 0.680851 (-2350 -6500);
PAINT MONO (-2350 -6500);
DISPLAY INVISIBLE (-2350 -6500);
FORCEPROP 0 LAST CDS_SEC 1
J 0
(-2350 -6500);
DISPLAY 0.680851 (-2350 -6500);
DISPLAY INVISIBLE (-2350 -6500);
FORCEPROP 1 LASTPIN (-2400 -6550) $PN 1
J 0
(-2390 -6570);
DISPLAY 0.787234 (-2390 -6570);
PAINT MONO (-2390 -6570);
FORCEPROP 1 LASTPIN (-2400 -6750) $PN 2
J 0
(-2390 -6770);
DISPLAY 0.787234 (-2390 -6770);
PAINT MONO (-2390 -6770);
FORCEPROP 1 LAST MATERIAL EMPTY
J 0
(-2350 -6750);
DISPLAY 0.489362 (-2350 -6750);
PAINT RED (-2350 -6750);
FORCEPROP 1 LAST PACK_TYPE C0402
J 0
(-2350 -6850);
DISPLAY 0.489362 (-2350 -6850);
PAINT SKYBLUE (-2350 -6850);
FORCEPROP 1 LAST VOLTAGE 50V
J 0
(-2350 -6650);
DISPLAY 0.489362 (-2350 -6650);
PAINT SKYBLUE (-2350 -6650);
FORCEPROP 1 LAST TOLERANCE 10%
J 0
(-2350 -6700);
DISPLAY 0.489362 (-2350 -6700);
PAINT SKYBLUE (-2350 -6700);
FORCEPROP 1 LAST VALUE 560PF
J 0
(-2350 -6600);
DISPLAY 0.489362 (-2350 -6600);
PAINT SKYBLUE (-2350 -6600);
FORCEPROP 2 LAST CDS_LIB pure_quanta
J 0
(-2400 -6650);
DISPLAY INVISIBLE (-2400 -6650);
FORCEPROP 1 LAST PART_NUMBER CH1566K1B09
J 0
(-2350 -6800);
DISPLAY 0.489362 (-2350 -6800);
PAINT SKYBLUE (-2350 -6800);
DISPLAY INVISIBLE (-2350 -6800);
FORCEPROP 1 LAST PATH I285
J 0
(-2350 -6500);
DISPLAY 0.978723 (-2350 -6500);
PAINT WHITE (-2350 -6500);
DISPLAY INVISIBLE (-2350 -6500);
FORCEADD Q_RES..2
(-2400 -10075);
FORCEPROP 1 LAST LOCATION PR6563
J 0
(-2350 -9950);
DISPLAY 0.617021 (-2350 -9950);
PAINT SKYBLUE (-2350 -9950);
FORCEPROP 0 LAST $SEC 1
J 0
(-2350 -9900);
DISPLAY 0.680851 (-2350 -9900);
PAINT MONO (-2350 -9900);
DISPLAY INVISIBLE (-2350 -9900);
FORCEPROP 0 LAST CDS_SEC 1
J 0
(-2350 -9900);
DISPLAY 0.680851 (-2350 -9900);
DISPLAY INVISIBLE (-2350 -9900);
FORCEPROP 1 LASTPIN (-2400 -9975) $PN 1
J 0
(-2395 -10013);
DISPLAY 0.787234 (-2395 -10013);
PAINT MONO (-2395 -10013);
FORCEPROP 1 LASTPIN (-2400 -10175) $PN 2
J 0
(-2395 -10165);
DISPLAY 0.787234 (-2395 -10165);
PAINT MONO (-2395 -10165);
FORCEPROP 1 LAST TOLERANCE 1%
J 0
(-2355 -10050);
DISPLAY 0.489362 (-2355 -10050);
PAINT SKYBLUE (-2355 -10050);
FORCEPROP 1 LAST VALUE 1.5
J 0
(-2355 -10000);
DISPLAY 0.489362 (-2355 -10000);
PAINT SKYBLUE (-2355 -10000);
FORCEPROP 1 LAST MATERIAL EMPTY
J 0
(-2360 -10150);
DISPLAY 0.489362 (-2360 -10150);
PAINT RED (-2360 -10150);
FORCEPROP 1 LAST PACK_TYPE 0402LF
J 0
(-2360 -10250);
DISPLAY 0.489362 (-2360 -10250);
PAINT SKYBLUE (-2360 -10250);
FORCEPROP 1 LAST WATTAGE 1/8W
J 0
(-2360 -10100);
DISPLAY 0.489362 (-2360 -10100);
PAINT SKYBLUE (-2360 -10100);
FORCEPROP 2 LAST CDS_LIB pure_quanta
J 0
(-2400 -10075);
DISPLAY INVISIBLE (-2400 -10075);
FORCEPROP 1 LAST PART_NUMBER CS-1504FB00
J 0
(-2360 -10200);
DISPLAY 0.489362 (-2360 -10200);
PAINT SKYBLUE (-2360 -10200);
DISPLAY INVISIBLE (-2360 -10200);
FORCEPROP 1 LAST PATH I286
J 0
(-2350 -9900);
DISPLAY 0.978723 (-2350 -9900);
PAINT WHITE (-2350 -9900);
DISPLAY INVISIBLE (-2350 -9900);
FORCEADD UNIVERSAL_GND..1
(-2400 -10300);
FORCEPROP 3 LASTPIN (-2400 -10250) SIG_NAME GND\g
J 0
(-2390 -10240);
DISPLAY 0.659574 (-2390 -10240);
PAINT MONO (-2390 -10240);
DISPLAY INVISIBLE (-2390 -10240);
FORCEPROP 2 LAST CDS_LIB pure_quanta_power
J 0
(-2400 -10300);
DISPLAY INVISIBLE (-2400 -10300);
FORCEPROP 1 LAST HDL_POWER GND
J 1
(-2375 -10375);
DISPLAY 0.872340 (-2375 -10375);
PAINT GREEN (-2375 -10375);
DISPLAY INVISIBLE (-2375 -10375);
FORCEPROP 1 LAST PATH I287
J 0
(-2325 -10300);
DISPLAY 0.872340 (-2325 -10300);
PAINT AQUA (-2325 -10300);
DISPLAY INVISIBLE (-2325 -10300);
FORCEADD Q_CAP..1
(-2400 -9550);
FORCEPROP 1 LAST LOCATION PC6585
J 0
(-2350 -9450);
DISPLAY 0.617021 (-2350 -9450);
PAINT SKYBLUE (-2350 -9450);
FORCEPROP 0 LAST $SEC 1
J 0
(-2350 -9400);
DISPLAY 0.680851 (-2350 -9400);
PAINT MONO (-2350 -9400);
DISPLAY INVISIBLE (-2350 -9400);
FORCEPROP 0 LAST CDS_SEC 1
J 0
(-2350 -9400);
DISPLAY 0.680851 (-2350 -9400);
DISPLAY INVISIBLE (-2350 -9400);
FORCEPROP 1 LASTPIN (-2400 -9450) $PN 1
J 0
(-2390 -9470);
DISPLAY 0.787234 (-2390 -9470);
PAINT MONO (-2390 -9470);
FORCEPROP 1 LASTPIN (-2400 -9650) $PN 2
J 0
(-2390 -9670);
DISPLAY 0.787234 (-2390 -9670);
PAINT MONO (-2390 -9670);
FORCEPROP 1 LAST VOLTAGE 50V
J 0
(-2350 -9550);
DISPLAY 0.489362 (-2350 -9550);
PAINT SKYBLUE (-2350 -9550);
FORCEPROP 1 LAST TOLERANCE 10%
J 0
(-2350 -9600);
DISPLAY 0.489362 (-2350 -9600);
PAINT SKYBLUE (-2350 -9600);
FORCEPROP 1 LAST MATERIAL EMPTY
J 0
(-2350 -9650);
DISPLAY 0.489362 (-2350 -9650);
PAINT RED (-2350 -9650);
FORCEPROP 1 LAST PACK_TYPE C0402
J 0
(-2350 -9750);
DISPLAY 0.489362 (-2350 -9750);
PAINT SKYBLUE (-2350 -9750);
FORCEPROP 1 LAST VALUE 560PF
J 0
(-2350 -9500);
DISPLAY 0.489362 (-2350 -9500);
PAINT SKYBLUE (-2350 -9500);
FORCEPROP 2 LAST CDS_LIB pure_quanta
J 0
(-2400 -9550);
DISPLAY INVISIBLE (-2400 -9550);
FORCEPROP 1 LAST PART_NUMBER CH1566K1B09
J 0
(-2350 -9700);
DISPLAY 0.489362 (-2350 -9700);
PAINT SKYBLUE (-2350 -9700);
DISPLAY INVISIBLE (-2350 -9700);
FORCEPROP 1 LAST PATH I288
J 0
(-2350 -9400);
DISPLAY 0.978723 (-2350 -9400);
PAINT WHITE (-2350 -9400);
DISPLAY INVISIBLE (-2350 -9400);
FORCEADD UNIVERSAL_POWER..1
(-5400 -5125);
FORCEPROP 3 LASTPIN (-5400 -5175) SIG_NAME P0V9_RETIMER_CPU0_PVCC\g
J 0
(-5390 -5165);
DISPLAY 0.659574 (-5390 -5165);
PAINT MONO (-5390 -5165);
DISPLAY INVISIBLE (-5390 -5165);
FORCEPROP 1 LAST HDL_POWER P0V9_RETIMER_CPU0_PVCC
J 1
(-5400 -5075);
DISPLAY 0.872340 (-5400 -5075);
PAINT GREEN (-5400 -5075);
FORCEPROP 2 LAST CDS_LIB pure_quanta_power
J 0
(-5400 -5125);
DISPLAY INVISIBLE (-5400 -5125);
FORCEPROP 1 LAST PATH I289
J 0
(-5350 -5100);
DISPLAY 0.872340 (-5350 -5100);
PAINT AQUA (-5350 -5100);
DISPLAY INVISIBLE (-5350 -5100);
FORCEADD Q_CAP..1
(-2500 -5650);
FORCEPROP 1 LAST LOCATION PC6554_1
J 0
(-2450 -5550);
DISPLAY 0.723404 (-2450 -5550);
FORCEPROP 2 LAST $SEC 1
J 0
(-2450 -5450);
DISPLAY 0.680851 (-2450 -5450);
PAINT MONO (-2450 -5450);
DISPLAY INVISIBLE (-2450 -5450);
FORCEPROP 2 LAST CDS_SEC 1
J 0
(-2450 -5450);
DISPLAY 0.680851 (-2450 -5450);
DISPLAY INVISIBLE (-2450 -5450);
FORCEPROP 1 LASTPIN (-2500 -5550) $PN 1
J 0
(-2490 -5570);
DISPLAY 0.617021 (-2490 -5570);
PAINT WHITE (-2490 -5570);
FORCEPROP 1 LASTPIN (-2500 -5750) $PN 2
J 0
(-2490 -5770);
DISPLAY 0.617021 (-2490 -5770);
PAINT WHITE (-2490 -5770);
FORCEPROP 1 LAST VALUE 1UF
J 0
(-2450 -5600);
DISPLAY 0.617021 (-2450 -5600);
FORCEPROP 1 LAST MATERIAL X6S
J 0
(-2450 -5750);
DISPLAY 0.617021 (-2450 -5750);
FORCEPROP 1 LAST TOLERANCE 10%
J 0
(-2450 -5700);
DISPLAY 0.617021 (-2450 -5700);
FORCEPROP 1 LAST PACK_TYPE C0402
J 0
(-2450 -5850);
DISPLAY 0.617021 (-2450 -5850);
FORCEPROP 1 LAST VOLTAGE 25V
J 0
(-2450 -5650);
DISPLAY 0.617021 (-2450 -5650);
FORCEPROP 2 LAST CDS_LIB pure_quanta
J 0
(-2500 -5650);
DISPLAY INVISIBLE (-2500 -5650);
FORCEPROP 2 LAST BOM_COST VR_DIMM 
J 0
(-2450 -5500);
DISPLAY 0.680851 (-2450 -5500);
DISPLAY INVISIBLE (-2450 -5500);
FORCEPROP 1 LAST PART_NUMBER CH5104KEB02
J 0
(-2450 -5800);
DISPLAY 0.617021 (-2450 -5800);
DISPLAY INVISIBLE (-2450 -5800);
FORCEPROP 1 LAST PATH I29
J 0
(-2450 -5500);
DISPLAY 0.978723 (-2450 -5500);
PAINT WHITE (-2450 -5500);
DISPLAY INVISIBLE (-2450 -5500);
FORCEADD UNIVERSAL_GND..1
(2000 -6000);
FORCEPROP 3 LASTPIN (2000 -5950) SIG_NAME GND\g
J 0
(2010 -5940);
DISPLAY 0.659574 (2010 -5940);
PAINT MONO (2010 -5940);
DISPLAY INVISIBLE (2010 -5940);
FORCEPROP 2 LAST CDS_LIB pure_quanta_power
J 0
(2000 -6000);
DISPLAY INVISIBLE (2000 -6000);
FORCEPROP 1 LAST HDL_POWER GND
J 1
(2025 -6075);
DISPLAY 0.872340 (2025 -6075);
PAINT GREEN (2025 -6075);
DISPLAY INVISIBLE (2025 -6075);
FORCEPROP 1 LAST PATH I290
J 0
(2075 -6000);
DISPLAY 0.872340 (2075 -6000);
PAINT AQUA (2075 -6000);
DISPLAY INVISIBLE (2075 -6000);
FORCEADD Q_CAP..1
(2000 -5675);
FORCEPROP 1 LAST LOCATION PC6562
J 0
(2050 -5575);
DISPLAY 0.489362 (2050 -5575);
PAINT SKYBLUE (2050 -5575);
FORCEPROP 0 LAST $SEC 1
J 0
(2050 -5550);
DISPLAY 0.680851 (2050 -5550);
PAINT MONO (2050 -5550);
DISPLAY INVISIBLE (2050 -5550);
FORCEPROP 0 LAST CDS_SEC 1
J 0
(2050 -5550);
DISPLAY 0.680851 (2050 -5550);
DISPLAY INVISIBLE (2050 -5550);
FORCEPROP 1 LASTPIN (2000 -5575) $PN 1
J 0
(2010 -5595);
DISPLAY 0.787234 (2010 -5595);
PAINT MONO (2010 -5595);
FORCEPROP 1 LASTPIN (2000 -5775) $PN 2
J 0
(2010 -5795);
DISPLAY 0.787234 (2010 -5795);
PAINT MONO (2010 -5795);
FORCEPROP 1 LAST MATERIAL X7R
J 0
(2050 -5775);
DISPLAY 0.489362 (2050 -5775);
PAINT SKYBLUE (2050 -5775);
FORCEPROP 1 LAST PACK_TYPE 0402
J 0
(2050 -5875);
DISPLAY 0.489362 (2050 -5875);
PAINT SKYBLUE (2050 -5875);
FORCEPROP 1 LAST VOLTAGE 25V
J 0
(2050 -5675);
DISPLAY 0.489362 (2050 -5675);
PAINT SKYBLUE (2050 -5675);
FORCEPROP 1 LAST VALUE 0.1UF
J 0
(2050 -5625);
DISPLAY 0.489362 (2050 -5625);
PAINT SKYBLUE (2050 -5625);
FORCEPROP 1 LAST TOLERANCE 10%
J 0
(2050 -5725);
DISPLAY 0.489362 (2050 -5725);
PAINT SKYBLUE (2050 -5725);
FORCEPROP 2 LAST CDS_LIB pure_quanta
J 0
(2000 -5675);
DISPLAY INVISIBLE (2000 -5675);
FORCEPROP 1 LAST PART_NUMBER CH4104K1B00
J 0
(2050 -5825);
DISPLAY 0.489362 (2050 -5825);
PAINT SKYBLUE (2050 -5825);
DISPLAY INVISIBLE (2050 -5825);
FORCEPROP 1 LAST PATH I291
J 0
(2050 -5525);
DISPLAY 0.978723 (2050 -5525);
PAINT WHITE (2050 -5525);
DISPLAY INVISIBLE (2050 -5525);
FORCEADD Q_CAP..2
(-1125 -6100);
FORCEPROP 1 LAST LOCATION PC6563
J 1
(-1125 -6000);
DISPLAY 0.723404 (-1125 -6000);
FORCEPROP 2 LAST $SEC 1
J 0
(-1125 -5850);
DISPLAY 0.680851 (-1125 -5850);
PAINT MONO (-1125 -5850);
DISPLAY INVISIBLE (-1125 -5850);
FORCEPROP 0 LAST CDS_SEC 1
J 0
(-1125 -5850);
DISPLAY 0.680851 (-1125 -5850);
PAINT MONO (-1125 -5850);
DISPLAY INVISIBLE (-1125 -5850);
FORCEPROP 1 LASTPIN (-1225 -6100) $PN 1
J 0
(-1235 -6085);
DISPLAY 0.617021 (-1235 -6085);
PAINT WHITE (-1235 -6085);
FORCEPROP 1 LASTPIN (-1025 -6100) $PN 2
J 0
(-1040 -6085);
DISPLAY 0.617021 (-1040 -6085);
PAINT WHITE (-1040 -6085);
FORCEPROP 1 LAST VOLTAGE 50V
J 0
(-1125 -6200);
DISPLAY 0.617021 (-1125 -6200);
FORCEPROP 1 LAST PACK_TYPE C0402
J 1
(-1125 -6300);
DISPLAY 0.617021 (-1125 -6300);
FORCEPROP 1 LAST TOLERANCE 10%
J 2
(-1125 -6250);
DISPLAY 0.617021 (-1125 -6250);
FORCEPROP 1 LAST MATERIAL X7R
J 0
(-1125 -6250);
DISPLAY 0.617021 (-1125 -6250);
FORCEPROP 1 LAST VALUE 100NF
J 2
(-1125 -6200);
DISPLAY 0.617021 (-1125 -6200);
FORCEPROP 2 LAST CDS_LIB pure_quanta
J 0
(-1125 -6100);
DISPLAY INVISIBLE (-1125 -6100);
FORCEPROP 0 LAST REUSE_ID 55
J 0
(-1150 -6000);
DISPLAY 0.680851 (-1150 -6000);
DISPLAY INVISIBLE (-1150 -6000);
FORCEPROP 2 LAST BOM_COST VR_DIMM 
J 0
(-1125 -5950);
DISPLAY 0.680851 (-1125 -5950);
DISPLAY INVISIBLE (-1125 -5950);
FORCEPROP 1 LAST PART_NUMBER CH4106K1B01
J 1
(-1125 -6050);
DISPLAY 0.617021 (-1125 -6050);
DISPLAY INVISIBLE (-1125 -6050);
FORCEPROP 1 LAST PATH I30
J 0
(-1125 -5900);
DISPLAY 0.978723 (-1125 -5900);
PAINT WHITE (-1125 -5900);
DISPLAY INVISIBLE (-1125 -5900);
FORCEADD Q_CAP..1
(-1150 -6600);
FORCEPROP 1 LAST LOCATION PC6565
J 0
(-1100 -6500);
DISPLAY 0.723404 (-1100 -6500);
FORCEPROP 2 LAST $SEC 1
J 0
(-1100 -6400);
DISPLAY 0.680851 (-1100 -6400);
PAINT MONO (-1100 -6400);
DISPLAY INVISIBLE (-1100 -6400);
FORCEPROP 0 LAST CDS_SEC 1
J 0
(-1100 -6400);
DISPLAY 0.680851 (-1100 -6400);
PAINT MONO (-1100 -6400);
DISPLAY INVISIBLE (-1100 -6400);
FORCEPROP 1 LASTPIN (-1150 -6500) $PN 1
J 0
(-1140 -6520);
DISPLAY 0.617021 (-1140 -6520);
PAINT WHITE (-1140 -6520);
FORCEPROP 1 LASTPIN (-1150 -6700) $PN 2
J 0
(-1140 -6720);
DISPLAY 0.617021 (-1140 -6720);
PAINT WHITE (-1140 -6720);
FORCEPROP 1 LAST MATERIAL X7R
J 0
(-1100 -6700);
DISPLAY 0.489362 (-1100 -6700);
FORCEPROP 1 LAST VOLTAGE 50V
J 0
(-1100 -6600);
DISPLAY 0.489362 (-1100 -6600);
FORCEPROP 1 LAST VALUE 100NF
J 0
(-1100 -6550);
DISPLAY 0.489362 (-1100 -6550);
FORCEPROP 1 LAST TOLERANCE 10%
J 0
(-1100 -6650);
DISPLAY 0.489362 (-1100 -6650);
FORCEPROP 1 LAST PACK_TYPE C0402
J 0
(-1100 -6800);
DISPLAY 0.489362 (-1100 -6800);
FORCEPROP 2 LAST CDS_LIB pure_quanta
J 0
(-1150 -6600);
DISPLAY INVISIBLE (-1150 -6600);
FORCEPROP 2 LAST BOM_COST VR_DIMM 
J 0
(-1100 -6450);
DISPLAY 0.680851 (-1100 -6450);
DISPLAY INVISIBLE (-1100 -6450);
FORCEPROP 1 LAST PART_NUMBER CH4106K1B01
J 0
(-1100 -6750);
DISPLAY 0.489362 (-1100 -6750);
DISPLAY INVISIBLE (-1100 -6750);
FORCEPROP 1 LAST PATH I33
J 0
(-1100 -6450);
DISPLAY 0.978723 (-1100 -6450);
PAINT WHITE (-1100 -6450);
DISPLAY INVISIBLE (-1100 -6450);
FORCEADD Q_INDUCTOR..1
(-1925 -6425);
FORCEPROP 1 LAST LOCATION PL6505
J 0
(-2225 -6400);
DISPLAY 0.723404 (-2225 -6400);
PAINT GREEN (-2225 -6400);
FORCEPROP 2 LAST SEC 1
J 0
(-2050 -6225);
DISPLAY 0.680851 (-2050 -6225);
PAINT MONO (-2050 -6225);
DISPLAY INVISIBLE (-2050 -6225);
FORCEPROP 2 LASTPIN (-2025 -6450) $PN 1
J 2
(-2035 -6440);
DISPLAY 0.680851 (-2035 -6440);
PAINT MONO (-2035 -6440);
FORCEPROP 2 LASTPIN (-1825 -6450) $PN 2
J 0
(-1815 -6440);
DISPLAY 0.680851 (-1815 -6440);
PAINT MONO (-1815 -6440);
FORCEPROP 2 LAST PACK_TYPE SMLF
J 0
(-1600 -6500);
DISPLAY 0.617021 (-1600 -6500);
FORCEPROP 2 LAST VALUE 120NH/69A
J 0
(-1750 -6425);
DISPLAY 0.617021 (-1750 -6425);
FORCEPROP 1 LAST MATERIAL IND
J 0
(-2225 -6450);
DISPLAY 0.723404 (-2225 -6450);
PAINT GREEN (-2225 -6450);
FORCEPROP 2 LAST CDS_LIB pure_quanta
J 0
(-1925 -6425);
DISPLAY INVISIBLE (-1925 -6425);
FORCEPROP 2 LAST SEC_TYPE SMLF
J 0
(-2050 -6225);
DISPLAY 1.021277 (-2050 -6225);
DISPLAY INVISIBLE (-2050 -6225);
FORCEPROP 2 LAST BOM_COST VR_DIMM 
J 0
(-1750 -6375);
DISPLAY 0.680851 (-1750 -6375);
DISPLAY INVISIBLE (-1750 -6375);
FORCEPROP 1 LAST NEEDS_NO_SIZE TRUE
J 0
(-1925 -6425);
DISPLAY 0.468085 (-1925 -6425);
PAINT GREEN (-1925 -6425);
DISPLAY INVISIBLE (-1925 -6425);
FORCEPROP 1 LAST PART_NUMBER CV+12^0EZ03
J 0
(-2225 -6500);
DISPLAY 0.723404 (-2225 -6500);
PAINT GREEN (-2225 -6500);
DISPLAY INVISIBLE (-2225 -6500);
FORCEPROP 1 LAST PATH I34
J 0
(-1850 -6370);
DISPLAY 0.723404 (-1850 -6370);
PAINT GREEN (-1850 -6370);
DISPLAY INVISIBLE (-1850 -6370);
FORCEADD UNIVERSAL_POWER..1
(2000 -5200);
FORCEPROP 3 LASTPIN (2000 -5250) SIG_NAME P12V_AUX\g
J 0
(2010 -5240);
DISPLAY 0.659574 (2010 -5240);
PAINT MONO (2010 -5240);
DISPLAY INVISIBLE (2010 -5240);
FORCEPROP 1 LAST HDL_POWER P12V_AUX
J 1
(2000 -5150);
DISPLAY 0.617021 (2000 -5150);
PAINT GREEN (2000 -5150);
FORCEPROP 2 LAST BOM_COST VR_DIMM 
J 0
(2000 -5100);
DISPLAY 0.617021 (2000 -5100);
PAINT PURPLE (2000 -5100);
DISPLAY INVISIBLE (2000 -5100);
FORCEPROP 2 LAST CDS_LIB pure_quanta_power
J 0
(2000 -5200);
DISPLAY INVISIBLE (2000 -5200);
FORCEPROP 1 LAST PATH I4
J 0
(2050 -5175);
DISPLAY 0.872340 (2050 -5175);
PAINT AQUA (2050 -5175);
DISPLAY INVISIBLE (2050 -5175);
FORCEADD Q_RES..1
(-2150 -7625);
FORCEPROP 1 LAST LOCATION PR6556
J 0
(-2225 -7700);
DISPLAY 0.723404 (-2225 -7700);
FORCEPROP 2 LAST $SEC 1
J 0
(-2200 -7425);
DISPLAY 0.680851 (-2200 -7425);
PAINT MONO (-2200 -7425);
DISPLAY INVISIBLE (-2200 -7425);
FORCEPROP 0 LAST CDS_SEC 1
J 0
(-2200 -7425);
DISPLAY 0.680851 (-2200 -7425);
PAINT MONO (-2200 -7425);
DISPLAY INVISIBLE (-2200 -7425);
FORCEPROP 1 LASTPIN (-2250 -7625) $PN 1
J 0
(-2238 -7613);
DISPLAY 0.617021 (-2238 -7613);
PAINT WHITE (-2238 -7613);
FORCEPROP 1 LASTPIN (-2050 -7625) $PN 2
J 0
(-2088 -7613);
DISPLAY 0.617021 (-2088 -7613);
PAINT WHITE (-2088 -7613);
FORCEPROP 1 LAST MATERIAL CHIP
J 0
(-2350 -7500);
DISPLAY 0.617021 (-2350 -7500);
FORCEPROP 1 LAST WATTAGE 1/16W
J 2
(-2050 -7500);
DISPLAY 0.617021 (-2050 -7500);
FORCEPROP 1 LAST TOLERANCE 5%
J 0
(-1925 -7625);
DISPLAY 0.617021 (-1925 -7625);
FORCEPROP 1 LAST VALUE 0
J 2
(-1975 -7625);
DISPLAY 0.617021 (-1975 -7625);
FORCEPROP 1 LAST PACK_TYPE 0402LF
J 0
(-2000 -7500);
DISPLAY 0.617021 (-2000 -7500);
FORCEPROP 2 LAST CDS_LIB pure_quanta
J 0
(-2150 -7625);
DISPLAY INVISIBLE (-2150 -7625);
FORCEPROP 2 LAST BOM_COST VR_DIMM 
J 0
(-2200 -7650);
DISPLAY 0.680851 (-2200 -7650);
DISPLAY INVISIBLE (-2200 -7650);
FORCEPROP 1 LAST PART_NUMBER CS00002JB13
J 0
(-2350 -7550);
DISPLAY 0.617021 (-2350 -7550);
DISPLAY INVISIBLE (-2350 -7550);
FORCEPROP 1 LAST PATH I42
J 0
(-2200 -7475);
DISPLAY 0.978723 (-2200 -7475);
PAINT WHITE (-2200 -7475);
DISPLAY INVISIBLE (-2200 -7475);
FORCEADD Q_CAP..1
(-5200 -5500);
FORCEPROP 1 LAST LOCATION PC6550_09P0_1
J 0
(-5150 -5400);
DISPLAY 0.723404 (-5150 -5400);
FORCEPROP 2 LAST $SEC 1
J 0
(-5150 -5300);
DISPLAY 0.680851 (-5150 -5300);
PAINT MONO (-5150 -5300);
DISPLAY INVISIBLE (-5150 -5300);
FORCEPROP 2 LAST CDS_SEC 1
J 0
(-5150 -5300);
DISPLAY 0.680851 (-5150 -5300);
DISPLAY INVISIBLE (-5150 -5300);
FORCEPROP 1 LASTPIN (-5200 -5400) $PN 1
J 0
(-5190 -5420);
DISPLAY 0.617021 (-5190 -5420);
PAINT WHITE (-5190 -5420);
FORCEPROP 1 LASTPIN (-5200 -5600) $PN 2
J 0
(-5190 -5620);
DISPLAY 0.617021 (-5190 -5620);
PAINT WHITE (-5190 -5620);
FORCEPROP 1 LAST MATERIAL X6S
J 0
(-5150 -5600);
DISPLAY 0.617021 (-5150 -5600);
FORCEPROP 1 LAST VOLTAGE 10V
J 0
(-5150 -5500);
DISPLAY 0.617021 (-5150 -5500);
FORCEPROP 1 LAST PACK_TYPE C0402
J 0
(-5150 -5700);
DISPLAY 0.617021 (-5150 -5700);
FORCEPROP 1 LAST TOLERANCE 10%
J 0
(-5150 -5550);
DISPLAY 0.617021 (-5150 -5550);
FORCEPROP 1 LAST VALUE 2.2UF
J 0
(-5150 -5450);
DISPLAY 0.617021 (-5150 -5450);
FORCEPROP 2 LAST CDS_LIB pure_quanta
J 0
(-5200 -5500);
DISPLAY INVISIBLE (-5200 -5500);
FORCEPROP 2 LAST BOM_COST VR_DIMM 
J 0
(-5150 -5350);
DISPLAY 0.680851 (-5150 -5350);
DISPLAY INVISIBLE (-5150 -5350);
FORCEPROP 1 LAST PART_NUMBER CH5222KEB01
J 0
(-5150 -5650);
DISPLAY 0.617021 (-5150 -5650);
DISPLAY INVISIBLE (-5150 -5650);
FORCEPROP 1 LAST PATH I47
J 0
(-5150 -5350);
DISPLAY 0.978723 (-5150 -5350);
PAINT WHITE (-5150 -5350);
DISPLAY INVISIBLE (-5150 -5350);
FORCEADD Q_CAP..1
(-5900 -6025);
FORCEPROP 1 LAST LOCATION PC6552
J 0
(-5850 -5925);
DISPLAY 0.723404 (-5850 -5925);
FORCEPROP 2 LAST $SEC 1
J 0
(-5850 -5825);
DISPLAY 0.680851 (-5850 -5825);
PAINT MONO (-5850 -5825);
DISPLAY INVISIBLE (-5850 -5825);
FORCEPROP 0 LAST CDS_SEC 1
J 0
(-5850 -5825);
DISPLAY 0.680851 (-5850 -5825);
PAINT MONO (-5850 -5825);
DISPLAY INVISIBLE (-5850 -5825);
FORCEPROP 1 LASTPIN (-5900 -5925) $PN 1
J 0
(-5890 -5945);
DISPLAY 0.617021 (-5890 -5945);
PAINT WHITE (-5890 -5945);
FORCEPROP 1 LASTPIN (-5900 -6125) $PN 2
J 0
(-5890 -6145);
DISPLAY 0.617021 (-5890 -6145);
PAINT WHITE (-5890 -6145);
FORCEPROP 1 LAST PACK_TYPE C0402
J 0
(-5850 -6175);
DISPLAY 0.617021 (-5850 -6175);
FORCEPROP 1 LAST VOLTAGE 10V
J 0
(-5850 -6025);
DISPLAY 0.617021 (-5850 -6025);
FORCEPROP 1 LAST MATERIAL X6S
J 0
(-5850 -6075);
DISPLAY 0.617021 (-5850 -6075);
FORCEPROP 1 LAST VALUE 2.2UF
J 0
(-5850 -5975);
DISPLAY 0.617021 (-5850 -5975);
FORCEPROP 2 LAST CDS_LIB pure_quanta
J 0
(-5900 -6025);
PAINT MONO (-5900 -6025);
DISPLAY INVISIBLE (-5900 -6025);
FORCEPROP 2 LAST BOM_COST VR_DIMM 
J 0
(-5850 -5875);
DISPLAY 0.680851 (-5850 -5875);
DISPLAY INVISIBLE (-5850 -5875);
FORCEPROP 1 LAST TOLERANCE 10%
J 0
(-5850 -6075);
DISPLAY 0.978723 (-5850 -6075);
PAINT SKYBLUE (-5850 -6075);
DISPLAY INVISIBLE (-5850 -6075);
FORCEPROP 1 LAST PART_NUMBER CH5222KEB01
J 0
(-5850 -6125);
DISPLAY 0.617021 (-5850 -6125);
DISPLAY INVISIBLE (-5850 -6125);
FORCEPROP 1 LAST PATH I48
J 0
(-5850 -5875);
DISPLAY 0.978723 (-5850 -5875);
PAINT WHITE (-5850 -5875);
DISPLAY INVISIBLE (-5850 -5875);
FORCEADD ISL99390FRZTR5935..1
(-4100 -6450);
FORCEPROP 1 LAST LOCATION PU6503
J 0
(-4400 -5575);
DISPLAY 0.723404 (-4400 -5575);
PAINT GREEN (-4400 -5575);
FORCEPROP 2 LAST SEC 1
J 0
(-4400 -5350);
DISPLAY 0.680851 (-4400 -5350);
PAINT MONO (-4400 -5350);
DISPLAY INVISIBLE (-4400 -5350);
FORCEPROP 2 LASTPIN (-3700 -6900) $PN 2
J 0
(-3690 -6890);
DISPLAY 0.680851 (-3690 -6890);
PAINT MONO (-3690 -6890);
FORCEPROP 2 LASTPIN (-3700 -6100) $PN 33
J 0
(-3690 -6090);
DISPLAY 0.680851 (-3690 -6090);
PAINT MONO (-3690 -6090);
FORCEPROP 2 LASTPIN (-4550 -6700) $PN 31
J 2
(-4560 -6690);
DISPLAY 0.680851 (-4560 -6690);
PAINT MONO (-4560 -6690);
FORCEPROP 2 LASTPIN (-4550 -6300) $PN 35
J 2
(-4560 -6290);
DISPLAY 0.680851 (-4560 -6290);
PAINT MONO (-4560 -6290);
FORCEPROP 2 LASTPIN (-3700 -6750) $PN 6
J 0
(-3690 -6740);
DISPLAY 0.680851 (-3690 -6740);
PAINT MONO (-3690 -6740);
FORCEPROP 2 LASTPIN (-3700 -6800) $PN 41
J 0
(-3690 -6790);
DISPLAY 0.680851 (-3690 -6790);
PAINT MONO (-3690 -6790);
FORCEPROP 2 LASTPIN (-4550 -6450) $PN 38
J 2
(-4560 -6440);
DISPLAY 0.680851 (-4560 -6440);
PAINT MONO (-4560 -6440);
FORCEPROP 2 LASTPIN (-4550 -6750) $PN 37
J 2
(-4560 -6740);
DISPLAY 0.680851 (-4560 -6740);
PAINT MONO (-4560 -6740);
FORCEPROP 2 LASTPIN (-3700 -6950) $PN 5
J 0
(-3690 -6940);
DISPLAY 0.680851 (-3690 -6940);
PAINT MONO (-3690 -6940);
FORCEPROP 2 LASTPIN (-3700 -7000) $PN 7_9-20_24
J 0
(-3690 -6990);
DISPLAY 0.680851 (-3690 -6990);
PAINT MONO (-3690 -6990);
FORCEPROP 2 LASTPIN (-3700 -7050) $PN 40
J 0
(-3690 -7040);
DISPLAY 0.680851 (-3690 -7040);
PAINT MONO (-3690 -7040);
FORCEPROP 2 LASTPIN (-3700 -6350) $PN 32
J 0
(-3690 -6340);
DISPLAY 0.680851 (-3690 -6340);
PAINT MONO (-3690 -6340);
FORCEPROP 2 LASTPIN (-4550 -5800) $PN 4
J 2
(-4560 -5790);
DISPLAY 0.680851 (-4560 -5790);
PAINT MONO (-4560 -5790);
FORCEPROP 2 LASTPIN (-4550 -7050) $PN 34
J 2
(-4560 -7040);
DISPLAY 0.680851 (-4560 -7040);
PAINT MONO (-4560 -7040);
FORCEPROP 2 LASTPIN (-4550 -6550) $PN 39
J 2
(-4560 -6540);
DISPLAY 0.680851 (-4560 -6540);
PAINT MONO (-4560 -6540);
FORCEPROP 2 LASTPIN (-3700 -6450) $PN 10_19
J 0
(-3690 -6440);
DISPLAY 0.680851 (-3690 -6440);
PAINT MONO (-3690 -6440);
FORCEPROP 2 LASTPIN (-4550 -6950) $PN 36
J 2
(-4560 -6940);
DISPLAY 0.680851 (-4560 -6940);
PAINT MONO (-4560 -6940);
FORCEPROP 2 LASTPIN (-4550 -6100) $PN 3
J 2
(-4560 -6090);
DISPLAY 0.680851 (-4560 -6090);
PAINT MONO (-4560 -6090);
FORCEPROP 2 LASTPIN (-3700 -5800) $PN 25_29
J 0
(-3690 -5790);
DISPLAY 0.680851 (-3690 -5790);
PAINT MONO (-3690 -5790);
FORCEPROP 2 LASTPIN (-3700 -5850) $PN 30
J 0
(-3690 -5840);
DISPLAY 0.680851 (-3690 -5840);
PAINT MONO (-3690 -5840);
FORCEPROP 2 LASTPIN (-3700 -6700) $PN 1
J 0
(-3690 -6690);
DISPLAY 0.680851 (-3690 -6690);
PAINT MONO (-3690 -6690);
FORCEPROP 1 LAST MATERIAL IC
J 0
(-4400 -5725);
DISPLAY 0.723404 (-4400 -5725);
PAINT GREEN (-4400 -5725);
FORCEPROP 2 LAST PART_TYPE SMLF
J 0
(-4400 -5400);
DISPLAY 0.680851 (-4400 -5400);
FORCEPROP 2 LAST VALUE ISL99390FRZ-TR5935
J 0
(-4400 -5475);
DISPLAY 0.617021 (-4400 -5475);
FORCEPROP 1 LAST CDS_LMAN_SYM_OUTLINE -300,700,250,-650
J 0
(-4100 -6450);
DISPLAY 0.468085 (-4100 -6450);
PAINT GREEN (-4100 -6450);
DISPLAY INVISIBLE (-4100 -6450);
FORCEPROP 2 LAST CDS_LIB pure_quanta
J 0
(-4100 -6450);
DISPLAY INVISIBLE (-4100 -6450);
FORCEPROP 2 LAST SEC_TYPE 
J 0
(-4400 -5350);
DISPLAY 1.021277 (-4400 -5350);
DISPLAY INVISIBLE (-4400 -5350);
FORCEPROP 2 LAST BOM_COST VR_DIMM 
J 0
(-4375 -5425);
DISPLAY 0.680851 (-4375 -5425);
DISPLAY INVISIBLE (-4375 -5425);
FORCEPROP 1 LAST NEEDS_NO_SIZE TRUE
J 0
(-4100 -6450);
DISPLAY 0.723404 (-4100 -6450);
PAINT GREEN (-4100 -6450);
DISPLAY INVISIBLE (-4100 -6450);
FORCEPROP 1 LAST PART_NUMBER AL099390004
J 0
(-4400 -5650);
DISPLAY 0.723404 (-4400 -5650);
PAINT GREEN (-4400 -5650);
DISPLAY INVISIBLE (-4400 -5650);
FORCEPROP 1 LAST PATH I53
J 0
(-4100 -6450);
DISPLAY 0.723404 (-4100 -6450);
PAINT GREEN (-4100 -6450);
DISPLAY INVISIBLE (-4100 -6450);
FORCEADD Q_RES..2
(-5900 -5500);
FORCEPROP 1 LAST LOCATION PR6552
J 0
(-5855 -5375);
DISPLAY 0.723404 (-5855 -5375);
FORCEPROP 0 LAST $SEC 1
J 0
(-5850 -5325);
DISPLAY 0.680851 (-5850 -5325);
PAINT MONO (-5850 -5325);
DISPLAY INVISIBLE (-5850 -5325);
FORCEPROP 0 LAST CDS_SEC 1
J 0
(-5850 -5325);
DISPLAY 0.680851 (-5850 -5325);
DISPLAY INVISIBLE (-5850 -5325);
FORCEPROP 1 LASTPIN (-5900 -5400) $PN 1
J 0
(-5895 -5438);
DISPLAY 0.617021 (-5895 -5438);
PAINT MONO (-5895 -5438);
FORCEPROP 1 LASTPIN (-5900 -5600) $PN 2
J 0
(-5895 -5590);
DISPLAY 0.617021 (-5895 -5590);
PAINT MONO (-5895 -5590);
FORCEPROP 1 LAST PACK_TYPE 0402LF
J 0
(-5860 -5675);
DISPLAY 0.617021 (-5860 -5675);
FORCEPROP 1 LAST VALUE 2.2
J 0
(-5855 -5425);
DISPLAY 0.617021 (-5855 -5425);
FORCEPROP 1 LAST TOLERANCE 5%
J 0
(-5855 -5475);
DISPLAY 0.617021 (-5855 -5475);
FORCEPROP 1 LAST MATERIAL CHIP
J 0
(-5860 -5575);
DISPLAY 0.617021 (-5860 -5575);
FORCEPROP 1 LAST WATTAGE 1/16W
J 0
(-5860 -5525);
DISPLAY 0.617021 (-5860 -5525);
FORCEPROP 2 LAST CDS_LIB pure_quanta
J 0
(-5900 -5500);
DISPLAY INVISIBLE (-5900 -5500);
FORCEPROP 2 LAST BOM_COST VR_DIMM 
J 0
(-5850 -5325);
DISPLAY 0.680851 (-5850 -5325);
DISPLAY INVISIBLE (-5850 -5325);
FORCEPROP 1 LAST PART_NUMBER TMP_QCS-2202JB25
J 0
(-5875 -5625);
DISPLAY 0.617021 (-5875 -5625);
DISPLAY INVISIBLE (-5875 -5625);
FORCEPROP 1 LAST PATH I58
J 0
(-5850 -5325);
DISPLAY 0.978723 (-5850 -5325);
PAINT WHITE (-5850 -5325);
DISPLAY INVISIBLE (-5850 -5325);
FORCEADD OFFPAGE..4
R 2
(-5931 -6550);
FORCEPROP 2 LAST $XR1 364 
J 0
(-6333 -6550);
DISPLAY 0.638298 (-6333 -6550);
PAINT MONO (-6333 -6550);
FORCEPROP 2 LAST $XR0 363 
J 0
(-6213 -6550);
DISPLAY 0.638298 (-6213 -6550);
PAINT MONO (-6213 -6550);
FORCEPROP 2 LAST CDS_LIB standard
J 0
(-5931 -6550);
PAINT MONO (-5931 -6550);
DISPLAY INVISIBLE (-5931 -6550);
FORCEPROP 2 LAST BOM_COST VR_DIMM 
J 0
(-6206 -6500);
DISPLAY 0.680851 (-6206 -6500);
DISPLAY INVISIBLE (-6206 -6500);
FORCEPROP 1 LAST OFFPAGE TRUE
J 2
(-6256 -6675);
DISPLAY 0.872340 (-6256 -6675);
PAINT GREEN (-6256 -6675);
DISPLAY INVISIBLE (-6256 -6675);
FORCEPROP 1 LAST COMMENT_BODY TRUE
J 2
(-5906 -6650);
DISPLAY 0.872340 (-5906 -6650);
PAINT GREEN (-5906 -6650);
DISPLAY INVISIBLE (-5906 -6650);
FORCEPROP 2 LAST PATH I59
J 0
(-6206 -6500);
DISPLAY 0.680851 (-6206 -6500);
DISPLAY INVISIBLE (-6206 -6500);
FORCEADD Q_CAP..1
(-3000 -5650);
FORCEPROP 1 LAST LOCATION PC6555_1
J 0
(-2950 -5550);
DISPLAY 0.723404 (-2950 -5550);
FORCEPROP 0 LAST $SEC 1
J 0
(-2950 -5500);
DISPLAY 0.680851 (-2950 -5500);
PAINT MONO (-2950 -5500);
DISPLAY INVISIBLE (-2950 -5500);
FORCEPROP 0 LAST CDS_SEC 1
J 0
(-2950 -5500);
DISPLAY 0.680851 (-2950 -5500);
DISPLAY INVISIBLE (-2950 -5500);
FORCEPROP 1 LASTPIN (-3000 -5550) $PN 1
J 0
(-2990 -5570);
DISPLAY 0.617021 (-2990 -5570);
PAINT WHITE (-2990 -5570);
FORCEPROP 1 LASTPIN (-3000 -5750) $PN 2
J 0
(-2990 -5770);
DISPLAY 0.617021 (-2990 -5770);
PAINT WHITE (-2990 -5770);
FORCEPROP 1 LAST MATERIAL X7R
J 0
(-2950 -5750);
DISPLAY 0.617021 (-2950 -5750);
FORCEPROP 1 LAST VOLTAGE 50V
J 0
(-2950 -5650);
DISPLAY 0.617021 (-2950 -5650);
FORCEPROP 1 LAST VALUE 3300PF
J 0
(-2950 -5600);
DISPLAY 0.617021 (-2950 -5600);
FORCEPROP 1 LAST TOLERANCE 10%
J 0
(-2950 -5700);
DISPLAY 0.617021 (-2950 -5700);
FORCEPROP 1 LAST PACK_TYPE 0402
J 0
(-2950 -5850);
DISPLAY 0.617021 (-2950 -5850);
FORCEPROP 2 LAST CDS_LIB pure_quanta
J 0
(-3000 -5650);
DISPLAY INVISIBLE (-3000 -5650);
FORCEPROP 2 LAST BOM_COST VR_DIMM 
J 0
(-2950 -5500);
DISPLAY 0.680851 (-2950 -5500);
DISPLAY INVISIBLE (-2950 -5500);
FORCEPROP 1 LAST PART_NUMBER TMP_QCH2336K1B12
J 0
(-2950 -5800);
DISPLAY 0.617021 (-2950 -5800);
DISPLAY INVISIBLE (-2950 -5800);
FORCEPROP 1 LAST PATH I6
J 0
(-2950 -5500);
DISPLAY 0.978723 (-2950 -5500);
PAINT WHITE (-2950 -5500);
DISPLAY INVISIBLE (-2950 -5500);
FORCEADD OFFPAGE..2
R 2
(-6450 -6450);
FORCEPROP 2 LAST $XR0 363 
J 0
(-6735 -6450);
DISPLAY 0.638298 (-6735 -6450);
PAINT MONO (-6735 -6450);
FORCEPROP 2 LAST CDS_LIB standard
J 0
(-6450 -6450);
PAINT MONO (-6450 -6450);
DISPLAY INVISIBLE (-6450 -6450);
FORCEPROP 2 LAST BOM_COST VR_DIMM 
J 0
(-6731 -6400);
DISPLAY 0.680851 (-6731 -6400);
DISPLAY INVISIBLE (-6731 -6400);
FORCEPROP 1 LAST OFFPAGE TRUE
J 2
(-6775 -6575);
DISPLAY 1.170213 (-6775 -6575);
PAINT GREEN (-6775 -6575);
DISPLAY INVISIBLE (-6775 -6575);
FORCEPROP 1 LAST COMMENT_BODY TRUE
J 2
(-6405 -6545);
DISPLAY 1.170213 (-6405 -6545);
PAINT GREEN (-6405 -6545);
DISPLAY INVISIBLE (-6405 -6545);
FORCEPROP 2 LAST PATH I60
J 0
(-6731 -6400);
DISPLAY 0.680851 (-6731 -6400);
DISPLAY INVISIBLE (-6731 -6400);
FORCEADD OFFPAGE..4
R 2
(-5375 -7050);
FORCEPROP 2 LAST $XR0 363 
J 0
(-5627 -7050);
DISPLAY 0.638298 (-5627 -7050);
PAINT MONO (-5627 -7050);
FORCEPROP 2 LAST CDS_LIB standard
J 0
(-5375 -7050);
PAINT MONO (-5375 -7050);
DISPLAY INVISIBLE (-5375 -7050);
FORCEPROP 2 LAST BOM_COST VR_DIMM 
J 0
(-5670 -7000);
DISPLAY 0.680851 (-5670 -7000);
DISPLAY INVISIBLE (-5670 -7000);
FORCEPROP 1 LAST OFFPAGE TRUE
J 2
(-5700 -7175);
DISPLAY 0.872340 (-5700 -7175);
PAINT GREEN (-5700 -7175);
DISPLAY INVISIBLE (-5700 -7175);
FORCEPROP 1 LAST COMMENT_BODY TRUE
J 2
(-5350 -7150);
DISPLAY 0.872340 (-5350 -7150);
PAINT GREEN (-5350 -7150);
DISPLAY INVISIBLE (-5350 -7150);
FORCEPROP 2 LAST PATH I61
J 0
(-5670 -7000);
DISPLAY 0.680851 (-5670 -7000);
DISPLAY INVISIBLE (-5670 -7000);
FORCEADD OFFPAGE..2
R 2
(-5400 -6950);
FORCEPROP 2 LAST $XR1 363 
J 0
(-5655 -6986);
DISPLAY 0.638298 (-5655 -6986);
PAINT MONO (-5655 -6986);
FORCEPROP 2 LAST $XR0 364 
J 0
(-5655 -6950);
DISPLAY 0.638298 (-5655 -6950);
PAINT MONO (-5655 -6950);
FORCEPROP 2 LAST CDS_LIB standard
J 0
(-5400 -6950);
PAINT MONO (-5400 -6950);
DISPLAY INVISIBLE (-5400 -6950);
FORCEPROP 2 LAST BOM_COST VR_DIMM 
J 0
(-5681 -6900);
DISPLAY 0.680851 (-5681 -6900);
DISPLAY INVISIBLE (-5681 -6900);
FORCEPROP 1 LAST OFFPAGE TRUE
J 2
(-5725 -7075);
DISPLAY 1.170213 (-5725 -7075);
PAINT GREEN (-5725 -7075);
DISPLAY INVISIBLE (-5725 -7075);
FORCEPROP 1 LAST COMMENT_BODY TRUE
J 2
(-5355 -7045);
DISPLAY 1.170213 (-5355 -7045);
PAINT GREEN (-5355 -7045);
DISPLAY INVISIBLE (-5355 -7045);
FORCEPROP 2 LAST PATH I62
J 0
(-5681 -6900);
DISPLAY 0.680851 (-5681 -6900);
DISPLAY INVISIBLE (-5681 -6900);
FORCEADD Q_CAP..1
(-6650 -6875);
FORCEPROP 1 LAST LOCATION PC6553_1
J 0
(-6600 -6775);
DISPLAY 0.723404 (-6600 -6775);
FORCEPROP 0 LAST $SEC 1
J 0
(-6600 -6725);
DISPLAY 0.680851 (-6600 -6725);
PAINT MONO (-6600 -6725);
DISPLAY INVISIBLE (-6600 -6725);
FORCEPROP 0 LAST CDS_SEC 1
J 0
(-6600 -6725);
DISPLAY 0.680851 (-6600 -6725);
DISPLAY INVISIBLE (-6600 -6725);
FORCEPROP 1 LASTPIN (-6650 -6775) $PN 1
J 0
(-6640 -6795);
DISPLAY 0.617021 (-6640 -6795);
PAINT MONO (-6640 -6795);
FORCEPROP 1 LASTPIN (-6650 -6975) $PN 2
J 0
(-6640 -6995);
DISPLAY 0.617021 (-6640 -6995);
PAINT MONO (-6640 -6995);
FORCEPROP 1 LAST PACK_TYPE C0402
J 0
(-6600 -7075);
DISPLAY 0.617021 (-6600 -7075);
FORCEPROP 1 LAST MATERIAL X7R
J 0
(-6600 -6975);
DISPLAY 0.617021 (-6600 -6975);
FORCEPROP 1 LAST TOLERANCE 10%
J 0
(-6600 -6925);
DISPLAY 0.617021 (-6600 -6925);
FORCEPROP 1 LAST VALUE 100NF
J 0
(-6600 -6825);
DISPLAY 0.617021 (-6600 -6825);
FORCEPROP 1 LAST VOLTAGE 50V
J 0
(-6600 -6875);
DISPLAY 0.617021 (-6600 -6875);
FORCEPROP 2 LAST CDS_LIB pure_quanta
J 0
(-6650 -6875);
DISPLAY INVISIBLE (-6650 -6875);
FORCEPROP 2 LAST BOM_COST VR_CPU
J 0
(-6600 -6725);
DISPLAY 0.680851 (-6600 -6725);
DISPLAY INVISIBLE (-6600 -6725);
FORCEPROP 1 LAST PART_NUMBER CH4106K1B01
J 0
(-6600 -7025);
DISPLAY 0.617021 (-6600 -7025);
DISPLAY INVISIBLE (-6600 -7025);
FORCEPROP 1 LAST PATH I68
J 0
(-6600 -6725);
DISPLAY 0.978723 (-6600 -6725);
PAINT WHITE (-6600 -6725);
DISPLAY INVISIBLE (-6600 -6725);
FORCEADD DNS..1
(-2425 -9575);
PAINT RED (-2425 -9575);
FORCEPROP 2 LAST CDS_LIB mstr_misc
J 0
(-2425 -9575);
DISPLAY INVISIBLE (-2425 -9575);
FORCEPROP 1 LAST COMMENT_BODY TRUE
R 1
J 0
(-2350 -9800);
DISPLAY 0.872340 (-2350 -9800);
PAINT GREEN (-2350 -9800);
DISPLAY INVISIBLE (-2350 -9800);
FORCEADD DNS..1
(-5525 -4675);
PAINT RED (-5525 -4675);
FORCEPROP 2 LAST CDS_LIB mstr_misc
J 0
(-5525 -4675);
DISPLAY INVISIBLE (-5525 -4675);
FORCEPROP 1 LAST COMMENT_BODY TRUE
R 1
J 0
(-5450 -4900);
DISPLAY 0.872340 (-5450 -4900);
PAINT GREEN (-5450 -4900);
DISPLAY INVISIBLE (-5450 -4900);
FORCEADD DNS..1
(-2425 -6675);
PAINT RED (-2425 -6675);
FORCEPROP 2 LAST CDS_LIB mstr_misc
J 0
(-2425 -6675);
DISPLAY INVISIBLE (-2425 -6675);
FORCEPROP 1 LAST COMMENT_BODY TRUE
R 1
J 0
(-2350 -6900);
DISPLAY 0.872340 (-2350 -6900);
PAINT GREEN (-2350 -6900);
DISPLAY INVISIBLE (-2350 -6900);
FORCEADD DNS..1
(-2425 -10050);
PAINT RED (-2425 -10050);
FORCEPROP 2 LAST CDS_LIB mstr_misc
J 0
(-2425 -10050);
DISPLAY INVISIBLE (-2425 -10050);
FORCEPROP 1 LAST COMMENT_BODY TRUE
R 1
J 0
(-2350 -10275);
DISPLAY 0.872340 (-2350 -10275);
PAINT GREEN (-2350 -10275);
DISPLAY INVISIBLE (-2350 -10275);
FORCEADD DNS..2
(-5875 -7025);
PAINT RED (-5875 -7025);
FORCEPROP 2 LAST CDS_LIB mstr_misc
J 0
(-5875 -7025);
DISPLAY INVISIBLE (-5875 -7025);
FORCEPROP 2 LAST BOM_COST VR_DIMM 
J 0
(-6225 -6900);
DISPLAY 0.680851 (-6225 -6900);
DISPLAY INVISIBLE (-6225 -6900);
FORCEPROP 1 LAST COMMENT_BODY TRUE
R 1
J 0
(-5800 -7250);
DISPLAY 0.872340 (-5800 -7250);
PAINT GREEN (-5800 -7250);
DISPLAY INVISIBLE (-5800 -7250);
FORCEADD DNS..2
(-5750 -9925);
PAINT RED (-5750 -9925);
FORCEPROP 2 LAST CDS_LIB mstr_misc
J 0
(-5750 -9925);
DISPLAY INVISIBLE (-5750 -9925);
FORCEPROP 2 LAST BOM_COST VR_DIMM 
J 0
(-6100 -9800);
DISPLAY 0.680851 (-6100 -9800);
DISPLAY INVISIBLE (-6100 -9800);
FORCEPROP 1 LAST COMMENT_BODY TRUE
R 1
J 0
(-5675 -10150);
DISPLAY 0.872340 (-5675 -10150);
PAINT GREEN (-5675 -10150);
DISPLAY INVISIBLE (-5675 -10150);
FORCEADD DNS..1
(-2425 -7150);
PAINT RED (-2425 -7150);
FORCEPROP 2 LAST CDS_LIB mstr_misc
J 0
(-2425 -7150);
DISPLAY INVISIBLE (-2425 -7150);
FORCEPROP 1 LAST COMMENT_BODY TRUE
R 1
J 0
(-2350 -7375);
DISPLAY 0.872340 (-2350 -7375);
PAINT GREEN (-2350 -7375);
DISPLAY INVISIBLE (-2350 -7375);
FORCEADD QUANTA_TITLE_BLOCK_C..1
(2400 -10775);
FORCEPROP 0 LAST CDS_CON_LAST_MODIFIED Thu Sep 14 16:13:02 2023
J 0
(515 -10760);
DISPLAY INVISIBLE (515 -10760);
FORCEPROP 1 LAST CUSTOM_TXT_CDS <CON_LAST_MODIFIED>
J 0
(515 -10760);
DISPLAY 0.978723 (515 -10760);
FORCEPROP 2 LAST CUSTOM_TXT_CDS <XR_PAGE_TITLE>
J 0
(-5490 -5525);
DISPLAY 0.638298 (-5490 -5525);
PAINT PINK (-5490 -5525);
DISPLAY INVISIBLE (-5490 -5525);
FORCEPROP 1 LAST CUSTOM_TXT_CDS <NAME_2>
J 0
(-775 -10725);
FORCEPROP 1 LAST CUSTOM_TXT_CDS <NAME_1>
J 0
(-775 -10600);
FORCEPROP 1 LAST CUSTOM_TXT_CDS <Q_NUMBER>
J 0
(997 -10672);
DISPLAY 1.212766 (997 -10672);
FORCEPROP 1 LAST CUSTOM_TXT_CDS <Q_PROJ>
J 0
(18 -10673);
DISPLAY 1.212766 (18 -10673);
FORCEPROP 1 LAST CUSTOM_TXT_CDS <Q_REV>
J 0
(2216 -10672);
DISPLAY 1.212766 (2216 -10672);
FORCEPROP 1 LAST CUSTOM_TXT_CDS <CON_PAGE_NUM> OF <CON_TOTAL_PAGES>
J 0
(1954 -10757);
DISPLAY 0.978723 (1954 -10757);
FORCEPROP 1 LAST Q_TITLE P0V9_CPU0_RT_2D VR  PHASE1 & 2
J 0
(-6966 -10749);
DISPLAY 2.446809 (-6966 -10749);
PAINT GREEN (-6966 -10749);
FORCEPROP 2 LAST CDS_LIB pure_quanta
J 0
(2400 -10775);
DISPLAY INVISIBLE (2400 -10775);
FORCEPROP 1 LAST CDS_LMAN_SYM_OUTLINE -9475,6775,100,-125
J 0
(2400 -10775);
DISPLAY 0.468085 (2400 -10775);
PAINT GREEN (2400 -10775);
DISPLAY INVISIBLE (2400 -10775);
FORCEPROP 2 LAST BOM_COST VR_DIMM 
J 0
(-775 -10575);
DISPLAY 0.680851 (-775 -10575);
DISPLAY INVISIBLE (-775 -10575);
FORCEPROP 2 LAST PAGE_BORDER TRUE
J 0
(-5490 -5525);
DISPLAY 0.638298 (-5490 -5525);
PAINT PINK (-5490 -5525);
DISPLAY INVISIBLE (-5490 -5525);
FORCEPROP 2 LAST CDS_XR_PAGE_TITLE CR-364 : @T6G_MB_LIB.T6G(SCH_1):PAGE364
J 0
(-5490 -5525);
DISPLAY 0.638298 (-5490 -5525);
PAINT PINK (-5490 -5525);
DISPLAY INVISIBLE (-5490 -5525);
FORCEPROP 1 LAST COMMENT_BODY TRUE
J 0
(2412 -10788);
DISPLAY 0.978723 (2412 -10788);
PAINT GREEN (2412 -10788);
DISPLAY INVISIBLE (2412 -10788);
FORCEPROP 1 LAST Q_DEPT CCBU
J 1
(-1363 -10726);
DISPLAY 1.957447 (-1363 -10726);
PAINT GREEN (-1363 -10726);
DISPLAY INVISIBLE (-1363 -10726);
WIRE 16 -1 (-6450 -4400)(-6450 -4550);
WIRE 16 -1 (-5550 -4400)(-5550 -4550);
WIRE 16 -1 (-6650 -7025)(-6650 -6975);
WIRE 16 -1 (-5850 -7100)(-5850 -7200);
WIRE 16 -1 (-5900 -6175)(-5900 -6125);
WIRE 16 -1 (-5200 -5600)(-5200 -5700);
WIRE 16 -1 (600 -5775)(600 -5900);
WIRE 16 -1 (-1025 -5875)(-1025 -5750);
WIRE 16 -1 (-1500 -5875)(-1500 -5750);
WIRE 16 -1 (-2000 -5875)(-2000 -5750);
WIRE 16 -1 (-3000 -5875)(-3000 -5750);
WIRE 16 -1 (-2500 -5750)(-2500 -5875);
WIRE 16 -1 (-650 -5750)(-650 -5875);
WIRE 16 -1 (-250 -5800)(-250 -5875);
WIRE 16 -1 (200 -5800)(200 -5875);
WIRE 16 -1 (725 -8675)(725 -8800);
WIRE 16 -1 (325 -8700)(325 -8775);
WIRE 16 -1 (-125 -8700)(-125 -8775);
WIRE 16 -1 (-525 -8650)(-525 -8775);
WIRE 16 -1 (-900 -8775)(-900 -8650);
WIRE 16 -1 (-1375 -8775)(-1375 -8650);
WIRE 16 -1 (-1875 -8775)(-1875 -8650);
WIRE 16 -1 (-2375 -8650)(-2375 -8775);
WIRE 16 -1 (-2875 -8775)(-2875 -8650);
WIRE 16 -1 (-5075 -8500)(-5075 -8600);
WIRE 16 -1 (-5775 -9075)(-5775 -9025);
WIRE 16 -1 (-5725 -10000)(-5725 -10100);
WIRE 16 -1 (-6525 -9925)(-6525 -9875);
WIRE 16 -1 (-2400 -7275)(-2400 -7350);
WIRE 16 -1 (-2400 -10175)(-2400 -10250);
WIRE 16 -1 (2000 -5775)(2000 -5950);
WIRE 16 -1 (2000 -5475)(2000 -5250);
WIRE 16 -1 (2000 -5475)(2000 -5575);
WIRE 16 -1 (1250 -5475)(2000 -5475);
WIRE 16 -1 (-4550 -6450)(-6400 -6450);
FORCEPROP 2 LAST SIG_NAME P0V9_RETIMER_CPU0_IMON1
J 0
(-5385 -6440);
DISPLAY 0.617021 (-5385 -6440);
WIRE 16 -1 (-6650 -6775)(-6650 -6625);
WIRE 16 -1 (-5250 -6625)(-6650 -6625);
WIRE 16 -1 (-5250 -6550)(-5250 -6625);
WIRE 16 -1 (-4550 -6550)(-5250 -6550);
WIRE 16 -1 (-5250 -6550)(-5881 -6550);
FORCEPROP 2 LAST SIG_NAME PV09_RETIMER_CPU0_VCCS
J 0
(-5360 -6540);
DISPLAY 0.617021 (-5360 -6540);
WIRE 16 -1 (1600 -6450)(975 -6450);
WIRE 16 -1 (1600 -6450)(1600 -6175);
WIRE 16 -1 (975 -6450)(975 -6525);
WIRE 16 -1 (975 -6450)(625 -6450);
WIRE 16 -1 (625 -6500)(625 -6450);
WIRE 16 -1 (375 -6450)(625 -6450);
WIRE 16 -1 (375 -6500)(375 -6450);
WIRE 16 -1 (50 -6450)(375 -6450);
WIRE 16 -1 (50 -6450)(50 -6500);
WIRE 16 -1 (50 -6450)(-150 -6450);
WIRE 16 -1 (-150 -6500)(-150 -6450);
WIRE 16 -1 (-150 -6450)(-375 -6450);
WIRE 16 -1 (-375 -6450)(-375 -6500);
WIRE 16 -1 (-600 -6450)(-375 -6450);
WIRE 16 -1 (-600 -6450)(-600 -6500);
WIRE 16 -1 (-825 -6450)(-600 -6450);
WIRE 16 -1 (-825 -6450)(-825 -6500);
WIRE 16 -1 (-825 -6450)(-1150 -6450);
WIRE 16 -1 (-1150 -6500)(-1150 -6450);
WIRE 16 -1 (-1150 -6450)(-1400 -6450);
WIRE 16 -1 (-1825 -6450)(-1400 -6450);
WIRE 16 -1 (-1400 -6450)(-1400 -7625);
WIRE 16 -1 (-1400 -7625)(-2050 -7625);
WIRE 16 -1 (-3700 -6900)(-3525 -6900);
WIRE 16 -1 (-3525 -6900)(-3525 -6950);
WIRE 16 -1 (-3525 -6950)(-3525 -7000);
WIRE 16 -1 (-3700 -6950)(-3525 -6950);
WIRE 16 -1 (-3525 -7000)(-3525 -7050);
WIRE 16 -1 (-3700 -7000)(-3525 -7000);
WIRE 16 -1 (-3700 -7050)(-3525 -7050);
WIRE 16 -1 (-3525 -7050)(-3525 -7200);
WIRE 16 -1 (975 -6825)(625 -6825);
WIRE 16 -1 (975 -6725)(975 -6825);
WIRE 16 -1 (975 -6825)(975 -6875);
WIRE 16 -1 (625 -6825)(625 -6700);
WIRE 16 -1 (375 -6825)(625 -6825);
WIRE 16 -1 (375 -6700)(375 -6825);
WIRE 16 -1 (50 -6825)(375 -6825);
WIRE 16 -1 (50 -6700)(50 -6825);
WIRE 16 -1 (50 -6825)(-150 -6825);
WIRE 16 -1 (-150 -6700)(-150 -6825);
WIRE 16 -1 (-150 -6825)(-375 -6825);
WIRE 16 -1 (-375 -6700)(-375 -6825);
WIRE 16 -1 (-600 -6825)(-375 -6825);
WIRE 16 -1 (-600 -6700)(-600 -6825);
WIRE 16 -1 (-825 -6825)(-600 -6825);
WIRE 16 -1 (-825 -6825)(-825 -6700);
WIRE 16 -1 (-825 -6825)(-1150 -6825);
WIRE 16 -1 (-1150 -6825)(-1150 -6700);
WIRE 16 -1 (600 -5575)(600 -5475);
WIRE 16 -1 (1050 -5475)(600 -5475);
WIRE 16 -1 (550 -5475)(600 -5475);
WIRE 16 -1 (550 -5300)(550 -5475);
WIRE 16 -1 (200 -5475)(550 -5475);
WIRE 16 -1 (200 -5600)(200 -5475);
WIRE 16 -1 (-250 -5475)(200 -5475);
WIRE 16 -1 (-250 -5600)(-250 -5475);
WIRE 16 -1 (-650 -5475)(-250 -5475);
WIRE 16 -1 (-650 -5550)(-650 -5475);
WIRE 16 -1 (-1025 -5475)(-650 -5475);
WIRE 16 -1 (-1025 -5550)(-1025 -5475);
WIRE 16 -1 (-1500 -5475)(-1025 -5475);
WIRE 16 -1 (-1500 -5550)(-1500 -5475);
WIRE 16 -1 (-2000 -5475)(-1500 -5475);
WIRE 16 -1 (-2000 -5550)(-2000 -5475);
WIRE 16 -1 (-2000 -5475)(-2500 -5475);
WIRE 16 -1 (-2500 -5550)(-2500 -5475);
WIRE 16 -1 (-3000 -5475)(-2500 -5475);
WIRE 16 -1 (-3000 -5475)(-3000 -5550);
WIRE 16 -1 (-3375 -5475)(-3000 -5475);
WIRE 16 -1 (-3375 -5800)(-3375 -5475);
WIRE 16 -1 (-3375 -5800)(-3375 -5850);
WIRE 16 -1 (-3375 -5800)(-3700 -5800);
WIRE 16 -1 (-3375 -5850)(-3700 -5850);
WIRE 16 -1 (725 -8475)(725 -8375);
WIRE 16 -1 (675 -8375)(725 -8375);
WIRE 16 -1 (675 -8200)(675 -8375);
WIRE 16 -1 (325 -8375)(675 -8375);
WIRE 16 -1 (325 -8500)(325 -8375);
WIRE 16 -1 (-125 -8375)(325 -8375);
WIRE 16 -1 (-125 -8500)(-125 -8375);
WIRE 16 -1 (-525 -8375)(-125 -8375);
WIRE 16 -1 (-525 -8450)(-525 -8375);
WIRE 16 -1 (-900 -8375)(-525 -8375);
WIRE 16 -1 (-900 -8450)(-900 -8375);
WIRE 16 -1 (-1375 -8375)(-900 -8375);
WIRE 16 -1 (-1375 -8450)(-1375 -8375);
WIRE 16 -1 (-1875 -8375)(-1375 -8375);
WIRE 16 -1 (-1875 -8450)(-1875 -8375);
WIRE 16 -1 (-1875 -8375)(-2375 -8375);
WIRE 16 -1 (-2375 -8450)(-2375 -8375);
WIRE 16 -1 (-2875 -8375)(-2375 -8375);
WIRE 16 -1 (-2875 -8375)(-2875 -8450);
WIRE 16 -1 (-3250 -8375)(-2875 -8375);
WIRE 16 -1 (-3250 -8700)(-3250 -8375);
WIRE 16 -1 (-3250 -8700)(-3575 -8700);
WIRE 16 -1 (-3250 -8700)(-3250 -8750);
WIRE 16 -1 (-3250 -8750)(-3575 -8750);
WIRE 16 -1 (750 -9350)(1725 -9350);
WIRE 16 -1 (750 -9350)(750 -9400);
WIRE 16 -1 (750 -9350)(500 -9350);
WIRE 16 -1 (1725 -9350)(1725 -9075);
WIRE 16 -1 (500 -9400)(500 -9350);
WIRE 16 -1 (175 -9350)(500 -9350);
WIRE 16 -1 (175 -9350)(175 -9400);
WIRE 16 -1 (175 -9350)(-25 -9350);
WIRE 16 -1 (-25 -9400)(-25 -9350);
WIRE 16 -1 (-25 -9350)(-250 -9350);
WIRE 16 -1 (-250 -9350)(-250 -9400);
WIRE 16 -1 (-475 -9350)(-250 -9350);
WIRE 16 -1 (-475 -9350)(-475 -9400);
WIRE 16 -1 (-700 -9350)(-475 -9350);
WIRE 16 -1 (-700 -9350)(-700 -9400);
WIRE 16 -1 (-700 -9350)(-1025 -9350);
WIRE 16 -1 (-1025 -9400)(-1025 -9350);
WIRE 16 -1 (-1300 -9350)(-1025 -9350);
WIRE 16 -1 (-1725 -9350)(-1300 -9350);
WIRE 16 -1 (-1300 -9350)(-1300 -10425);
WIRE 16 -1 (-1300 -10425)(-1850 -10425);
WIRE 16 -1 (500 -9600)(500 -9725);
WIRE 16 -1 (500 -9725)(750 -9725);
WIRE 16 -1 (175 -9725)(500 -9725);
WIRE 16 -1 (175 -9600)(175 -9725);
WIRE 16 -1 (175 -9725)(-25 -9725);
WIRE 16 -1 (750 -9725)(750 -9600);
WIRE 16 -1 (750 -9725)(750 -9800);
WIRE 16 -1 (-25 -9600)(-25 -9725);
WIRE 16 -1 (-25 -9725)(-250 -9725);
WIRE 16 -1 (-250 -9600)(-250 -9725);
WIRE 16 -1 (-475 -9725)(-250 -9725);
WIRE 16 -1 (-475 -9600)(-475 -9725);
WIRE 16 -1 (-700 -9725)(-475 -9725);
WIRE 16 -1 (-700 -9725)(-700 -9600);
WIRE 16 -1 (-700 -9725)(-1025 -9725);
WIRE 16 -1 (-1025 -9725)(-1025 -9600);
WIRE 16 -1 (-3575 -9800)(-3400 -9800);
WIRE 16 -1 (-3400 -9800)(-3400 -9850);
WIRE 16 -1 (-3400 -9850)(-3400 -9900);
WIRE 16 -1 (-3575 -9850)(-3400 -9850);
WIRE 16 -1 (-3400 -9900)(-3400 -9950);
WIRE 16 -1 (-3575 -9900)(-3400 -9900);
WIRE 16 -1 (-3575 -9950)(-3400 -9950);
WIRE 16 -1 (-3400 -9950)(-3400 -10100);
WIRE 16 -1 (-4525 -8700)(-4525 -8200);
WIRE 16 -1 (-4525 -8700)(-4425 -8700);
WIRE 16 -1 (-4525 -8200)(-5075 -8200);
WIRE 16 -1 (-5075 -8200)(-5075 -8300);
WIRE 16 -1 (-5075 -8200)(-5775 -8200);
WIRE 16 -1 (-5775 -8200)(-5775 -7800);
WIRE 16 -1 (-5775 -8200)(-5775 -8300);
WIRE 16 -1 (-4650 -5800)(-4550 -5800);
WIRE 16 -1 (-4650 -5800)(-4650 -5300);
WIRE 16 -1 (-4650 -5300)(-5200 -5300);
WIRE 16 -1 (-5200 -5300)(-5200 -5400);
WIRE 16 -1 (-5200 -5300)(-5400 -5300);
WIRE 16 -1 (-5400 -5175)(-5400 -5300);
WIRE 16 -1 (-5400 -5300)(-5900 -5300);
WIRE 16 -1 (-5900 -5300)(-5900 -4900);
WIRE 16 -1 (-5900 -5300)(-5900 -5400);
WIRE 16 -1 (-5550 -4900)(-5900 -4900);
WIRE 16 -1 (-5900 -4900)(-6450 -4900);
WIRE 16 -1 (-6450 -4900)(-6450 -4750);
WIRE 16 -1 (-5550 -4750)(-5550 -4900);
WIRE 16 -1 (-2025 -6450)(-2400 -6450);
WIRE 16 -1 (-2400 -6550)(-2400 -6450);
WIRE 16 -1 (-2400 -6450)(-3700 -6450);
FORCEPROP 2 LAST SIG_NAME SW_P0V9_RETIMER_CPU0_SW1
J 0
(-3535 -6440);
DISPLAY 0.617021 (-3535 -6440);
FORCEPROP 2 LASTPROP $XRERR UNIQUE?
J 0
(-3775 -6440);
DISPLAY 0.638298 (-3775 -6440);
PAINT MONO (-3775 -6440);
DISPLAY INVISIBLE (-3775 -6440);
WIRE 16 -1 (-4650 -6100)(-4650 -5850);
WIRE 16 -1 (-4550 -6100)(-4650 -6100);
WIRE 16 -1 (-4650 -6100)(-4650 -6300);
WIRE 16 -1 (-4650 -5850)(-5900 -5850);
FORCEPROP 2 LAST SIG_NAME P0V9_RETIMER_CPU0_VCC1
J 0
(-5360 -5840);
DISPLAY 0.617021 (-5360 -5840);
FORCEPROP 2 LASTPROP $XRERR UNIQUE?
J 0
(-5600 -5840);
DISPLAY 0.638298 (-5600 -5840);
PAINT MONO (-5600 -5840);
DISPLAY INVISIBLE (-5600 -5840);
WIRE 16 -1 (-5900 -5600)(-5900 -5850);
WIRE 16 -1 (-5900 -5850)(-5900 -5925);
WIRE 16 -1 (-4550 -6300)(-4650 -6300);
WIRE 16 -1 (-3700 -6100)(-2600 -6100);
FORCEPROP 2 LAST SIG_NAME SW_P0V9_RETIMER_CPU0_BOOT1
J 0
(-3535 -6090);
DISPLAY 0.617021 (-3535 -6090);
FORCEPROP 2 LASTPROP $XRERR UNIQUE?
J 0
(-3775 -6090);
DISPLAY 0.638298 (-3775 -6090);
PAINT MONO (-3775 -6090);
DISPLAY INVISIBLE (-3775 -6090);
WIRE 16 -1 (-3700 -6350)(-900 -6350);
FORCEPROP 2 LAST SIG_NAME SW_P0V9_RETIMER_CPU0_PH1
J 0
(-3535 -6340);
DISPLAY 0.617021 (-3535 -6340);
FORCEPROP 2 LASTPROP $XRERR UNIQUE?
J 0
(-3775 -6340);
DISPLAY 0.638298 (-3775 -6340);
PAINT MONO (-3775 -6340);
DISPLAY INVISIBLE (-3775 -6340);
WIRE 16 -1 (-900 -6100)(-900 -6350);
WIRE 16 -1 (-1025 -6100)(-900 -6100);
WIRE 16 -1 (-2725 -7625)(-2725 -6700);
WIRE 16 -1 (-2250 -7625)(-2725 -7625);
WIRE 16 -1 (-2725 -6700)(-3700 -6700);
FORCEPROP 2 LAST SIG_NAME P0V9_RETIMER_CPU0_VOS1
J 0
(-3585 -6690);
DISPLAY 0.617021 (-3585 -6690);
FORCEPROP 2 LASTPROP $XRERR UNIQUE?
J 0
(-3825 -6690);
DISPLAY 0.638298 (-3825 -6690);
PAINT MONO (-3825 -6690);
DISPLAY INVISIBLE (-3825 -6690);
WIRE 16 -1 (-2400 -6100)(-1225 -6100);
FORCEPROP 2 LAST SIG_NAME SW_P0V9_RETIMER_CPU0_BOOT1_RC
J 0
(-2160 -6090);
DISPLAY 0.617021 (-2160 -6090);
FORCEPROP 2 LASTPROP $XRERR UNIQUE?
J 0
(-2400 -6090);
DISPLAY 0.638298 (-2400 -6090);
PAINT MONO (-2400 -6090);
DISPLAY INVISIBLE (-2400 -6090);
WIRE 16 -1 (-3575 -9000)(-2475 -9000);
FORCEPROP 2 LAST SIG_NAME SW_P0V9_RETIMER_CPU0_BOOT2
J 0
(-3435 -8990);
DISPLAY 0.617021 (-3435 -8990);
FORCEPROP 2 LASTPROP $XRERR UNIQUE?
J 0
(-3675 -8990);
DISPLAY 0.638298 (-3675 -8990);
PAINT MONO (-3675 -8990);
DISPLAY INVISIBLE (-3675 -8990);
WIRE 16 -1 (-2275 -9000)(-1100 -9000);
FORCEPROP 2 LAST SIG_NAME SW_P0V9_RETIMER_CPU0_BOOT2_RC
J 0
(-2035 -8990);
DISPLAY 0.617021 (-2035 -8990);
FORCEPROP 2 LASTPROP $XRERR UNIQUE?
J 0
(-2275 -8990);
DISPLAY 0.638298 (-2275 -8990);
PAINT MONO (-2275 -8990);
DISPLAY INVISIBLE (-2275 -8990);
WIRE 16 -1 (-3000 -6750)(-3700 -6750);
FORCEPROP 2 LAST SIG_NAME NC_PV09_RETIMER_CPU0_GL1_1
J 0
(-3585 -6740);
DISPLAY 0.617021 (-3585 -6740);
FORCEPROP 2 LASTPROP $XRERR UNIQUE?
J 0
(-2970 -6750);
DISPLAY 0.638298 (-2970 -6750);
PAINT MONO (-2970 -6750);
DISPLAY INVISIBLE (-2970 -6750);
WIRE 16 -1 (-5350 -6950)(-4550 -6950);
FORCEPROP 2 LAST SIG_NAME P0V9_RETIMER_CPU0_TEMP0
J 0
(-5335 -6940);
DISPLAY 0.617021 (-5335 -6940);
WIRE 16 -1 (-5325 -7050)(-4550 -7050);
FORCEPROP 2 LAST SIG_NAME P0V9_RETIMER_CPU0_PWM1
J 0
(-5310 -7040);
DISPLAY 0.617021 (-5310 -7040);
WIRE 16 -1 (-5225 -9850)(-4425 -9850);
FORCEPROP 2 LAST SIG_NAME P0V9_RETIMER_CPU0_TEMP0
J 0
(-5235 -9840);
DISPLAY 0.617021 (-5235 -9840);
WIRE 16 -1 (-4425 -9600)(-5125 -9600);
FORCEPROP 2 LAST SIG_NAME NC_PV09_RETIMER_CPU0_DNC2
J 0
(-5335 -9590);
DISPLAY 0.617021 (-5335 -9590);
FORCEPROP 2 LASTPROP $XRERR UNIQUE?
J 0
(-5365 -9600);
DISPLAY 0.638298 (-5365 -9600);
PAINT MONO (-5365 -9600);
DISPLAY INVISIBLE (-5365 -9600);
WIRE 16 -1 (-4425 -9350)(-6275 -9350);
FORCEPROP 2 LAST SIG_NAME P0V9_RETIMER_CPU0_IMON2
J 0
(-5260 -9340);
DISPLAY 0.617021 (-5260 -9340);
WIRE 16 -1 (-1925 -9350)(-2400 -9350);
WIRE 16 -1 (-2400 -9450)(-2400 -9350);
WIRE 16 -1 (-2400 -9350)(-3575 -9350);
FORCEPROP 2 LAST SIG_NAME SW_P0V9_RETIMER_CPU0_SW2
J 0
(-3435 -9340);
DISPLAY 0.617021 (-3435 -9340);
FORCEPROP 2 LASTPROP $XRERR UNIQUE?
J 0
(-3675 -9340);
DISPLAY 0.638298 (-3675 -9340);
PAINT MONO (-3675 -9340);
DISPLAY INVISIBLE (-3675 -9340);
WIRE 16 -1 (-2875 -9700)(-3575 -9700);
FORCEPROP 2 LAST SIG_NAME NC_PV09_RETIMER_CPU0_GL2_2
J 0
(-3435 -9690);
DISPLAY 0.617021 (-3435 -9690);
FORCEPROP 2 LASTPROP $XRERR UNIQUE?
J 0
(-2845 -9700);
DISPLAY 0.638298 (-2845 -9700);
PAINT MONO (-2845 -9700);
DISPLAY INVISIBLE (-2845 -9700);
WIRE 16 -1 (-2875 -9650)(-3575 -9650);
FORCEPROP 2 LAST SIG_NAME NC_PV09_RETIMER_CPU0_GL1_2
J 0
(-3435 -9640);
DISPLAY 0.617021 (-3435 -9640);
FORCEPROP 2 LASTPROP $XRERR UNIQUE?
J 0
(-2845 -9650);
DISPLAY 0.638298 (-2845 -9650);
PAINT MONO (-2845 -9650);
DISPLAY INVISIBLE (-2845 -9650);
WIRE 16 -1 (-2400 -9650)(-2400 -9975);
FORCEPROP 2 LAST SIG_NAME SW_P0V9_RETIMER_CPU0_SW2_RC
J 0
(-2360 -9840);
DISPLAY 0.489362 (-2360 -9840);
FORCEPROP 2 LASTPROP $XRERR UNIQUE?
J 0
(-2600 -9840);
DISPLAY 0.638298 (-2600 -9840);
PAINT MONO (-2600 -9840);
DISPLAY INVISIBLE (-2600 -9840);
WIRE 16 -1 (-2400 -6750)(-2400 -7075);
FORCEPROP 2 LAST SIG_NAME SW_P0V9_RETIMER_CPU0_SW1_RC
J 0
(-2360 -6940);
DISPLAY 0.489362 (-2360 -6940);
FORCEPROP 2 LASTPROP $XRERR UNIQUE?
J 0
(-2600 -6940);
DISPLAY 0.638298 (-2600 -6940);
PAINT MONO (-2600 -6940);
DISPLAY INVISIBLE (-2600 -6940);
WIRE 16 -1 (-4550 -6700)(-5250 -6700);
FORCEPROP 2 LAST SIG_NAME NC_PV09_RETIMER_CPU0_DNC1
J 0
(-5435 -6690);
DISPLAY 0.617021 (-5435 -6690);
FORCEPROP 2 LASTPROP $XRERR UNIQUE?
J 0
(-5490 -6700);
DISPLAY 0.638298 (-5490 -6700);
PAINT MONO (-5490 -6700);
DISPLAY INVISIBLE (-5490 -6700);
WIRE 16 -1 (-5850 -6750)(-4550 -6750);
FORCEPROP 0 LAST SIG_NAME P0V9_RETIMER_CPU0_LSET1
J 0
(-5385 -6740);
DISPLAY 0.617021 (-5385 -6740);
FORCEPROP 2 LASTPROP $XRERR UNIQUE?
J 0
(-5625 -6740);
DISPLAY 0.638298 (-5625 -6740);
PAINT MONO (-5625 -6740);
DISPLAY INVISIBLE (-5625 -6740);
WIRE 16 -1 (-5850 -6750)(-5850 -6900);
WIRE 16 -1 (-2050 -10425)(-2625 -10425);
WIRE 16 -1 (-2625 -10425)(-2625 -9600);
WIRE 16 -1 (-2625 -9600)(-3575 -9600);
FORCEPROP 2 LAST SIG_NAME P0V9_RETIMER_CPU0_VOS2
J 0
(-3435 -9590);
DISPLAY 0.617021 (-3435 -9590);
FORCEPROP 2 LASTPROP $XRERR UNIQUE?
J 0
(-3675 -9590);
DISPLAY 0.638298 (-3675 -9590);
PAINT MONO (-3675 -9590);
DISPLAY INVISIBLE (-3675 -9590);
WIRE 16 -1 (-5200 -9950)(-4425 -9950);
FORCEPROP 2 LAST SIG_NAME P0V9_RETIMER_CPU0_PWM2
J 0
(-5210 -9940);
DISPLAY 0.617021 (-5210 -9940);
WIRE 16 -1 (-5725 -9650)(-4425 -9650);
FORCEPROP 0 LAST SIG_NAME P0V9_RETIMER_CPU0_LSET2
J 0
(-5285 -9640);
DISPLAY 0.617021 (-5285 -9640);
FORCEPROP 2 LASTPROP $XRERR UNIQUE?
J 0
(-5525 -9640);
DISPLAY 0.638298 (-5525 -9640);
PAINT MONO (-5525 -9640);
DISPLAY INVISIBLE (-5525 -9640);
WIRE 16 -1 (-5725 -9650)(-5725 -9800);
WIRE 16 -1 (-4425 -9450)(-5125 -9450);
FORCEPROP 2 LAST SIG_NAME PV09_RETIMER_CPU0_VCCS
J 0
(-5235 -9440);
DISPLAY 0.617021 (-5235 -9440);
WIRE 16 -1 (-5125 -9450)(-5125 -9525);
WIRE 16 -1 (-5125 -9450)(-5756 -9450);
WIRE 16 -1 (-5125 -9525)(-6525 -9525);
WIRE 16 -1 (-6525 -9675)(-6525 -9525);
WIRE 16 -1 (-3575 -9250)(-775 -9250);
FORCEPROP 2 LAST SIG_NAME SW_P0V9_RETIMER_CPU0_PH2
J 0
(-3435 -9240);
DISPLAY 0.617021 (-3435 -9240);
FORCEPROP 2 LASTPROP $XRERR UNIQUE?
J 0
(-3675 -9240);
DISPLAY 0.638298 (-3675 -9240);
PAINT MONO (-3675 -9240);
DISPLAY INVISIBLE (-3675 -9240);
WIRE 16 -1 (-775 -9000)(-775 -9250);
WIRE 16 -1 (-900 -9000)(-775 -9000);
WIRE 16 -1 (-3000 -6800)(-3700 -6800);
FORCEPROP 2 LAST SIG_NAME NC_PV09_RETIMER_CPU0_GL2_1
J 0
(-3585 -6790);
DISPLAY 0.617021 (-3585 -6790);
FORCEPROP 2 LASTPROP $XRERR UNIQUE?
J 0
(-2970 -6800);
DISPLAY 0.638298 (-2970 -6800);
PAINT MONO (-2970 -6800);
DISPLAY INVISIBLE (-2970 -6800);
WIRE 16 -1 (-4525 -9000)(-4525 -8750);
WIRE 16 -1 (-4525 -9000)(-4525 -9200);
WIRE 16 -1 (-4425 -9000)(-4525 -9000);
WIRE 16 -1 (-4525 -8750)(-5775 -8750);
FORCEPROP 2 LAST SIG_NAME P0V9_RETIMER_CPU0_VCC2
J 0
(-5235 -8740);
DISPLAY 0.617021 (-5235 -8740);
FORCEPROP 2 LASTPROP $XRERR UNIQUE?
J 0
(-5475 -8740);
DISPLAY 0.638298 (-5475 -8740);
PAINT MONO (-5475 -8740);
DISPLAY INVISIBLE (-5475 -8740);
WIRE 16 -1 (-5775 -8500)(-5775 -8750);
WIRE 16 -1 (-5775 -8750)(-5775 -8825);
WIRE 16 -1 (-4425 -9200)(-4525 -9200);
DOT 1 (750 -9350);
DOT 1 (750 -9725);
DOT 1 (175 -9725);
DOT 1 (175 -9350);
DOT 1 (-25 -9350);
DOT 1 (-25 -9725);
DOT 1 (500 -9725);
DOT 1 (-1300 -9350);
DOT 1 (-700 -9725);
DOT 1 (375 -6450);
DOT 1 (625 -6825);
DOT 1 (625 -6450);
DOT 1 (-1150 -6450);
DOT 1 (2000 -5475);
DOT 1 (550 -5475);
DOT 1 (-3400 -9900);
DOT 1 (-5900 -4900);
DOT 1 (-5200 -5300);
DOT 1 (-5400 -5300);
DOT 1 (-5900 -5300);
DOT 1 (-2400 -9350);
DOT 1 (-1400 -6450);
DOT 1 (-2400 -6450);
DOT 1 (-3525 -7050);
DOT 1 (200 -5475);
DOT 1 (975 -6825);
DOT 1 (50 -6450);
DOT 1 (50 -6825);
DOT 1 (325 -8375);
DOT 1 (-250 -5475);
DOT 1 (-650 -5475);
DOT 1 (-1025 -5475);
DOT 1 (-2000 -5475);
DOT 1 (-150 -6450);
DOT 1 (-150 -6825);
DOT 1 (-825 -6450);
DOT 1 (-2500 -5475);
DOT 1 (-3000 -5475);
DOT 1 (-3525 -6950);
DOT 1 (-3525 -7000);
DOT 1 (-4650 -6100);
DOT 1 (-5250 -6550);
DOT 1 (-125 -8375);
DOT 1 (-900 -8375);
DOT 1 (-475 -9725);
DOT 1 (-700 -9350);
DOT 1 (-1375 -8375);
DOT 1 (-1025 -9350);
DOT 1 (-3400 -9850);
DOT 1 (-3400 -9950);
DOT 1 (-4525 -9000);
DOT 1 (-5775 -8200);
DOT 1 (-5775 -8750);
DOT 1 (-5125 -9450);
DOT 1 (-5900 -5850);
DOT 1 (-825 -6825);
DOT 1 (-600 -6825);
DOT 1 (-375 -6450);
DOT 1 (-375 -6825);
DOT 1 (-600 -6450);
DOT 1 (-1500 -5475);
DOT 1 (-5075 -8200);
DOT 1 (-250 -9725);
DOT 1 (-250 -9350);
DOT 1 (-475 -9350);
DOT 1 (-525 -8375);
DOT 1 (-2875 -8375);
DOT 1 (-3250 -8700);
DOT 1 (-2375 -8375);
DOT 1 (-1875 -8375);
DOT 1 (675 -8375);
DOT 1 (375 -6825);
DOT 1 (500 -9350);
DOT 1 (975 -6450);
DOT 1 (600 -5475);
DOT 1 (-3375 -5800);
FORCENOTE
PU6503,PU6504 = AL021590000 / TDA21590
(-1175 -4575) 0;
DISPLAY LEFT (-1175 -4575);
DISPLAY 1.021277 (-1175 -4575);
PAINT WHITE (-1175 -4575);
FORCENOTE
PR6554,PR6562,PR6553,PR6561 = CS00002JB13
(-1175 -4650) 0;
DISPLAY LEFT (-1175 -4650);
DISPLAY 1.021277 (-1175 -4650);
PAINT WHITE (-1175 -4650);
FORCENOTE
PR6556,PR6564,PR6557 = EMPTY
(-1175 -4725) 0;
DISPLAY LEFT (-1175 -4725);
DISPLAY 1.021277 (-1175 -4725);
PAINT WHITE (-1175 -4725);
FORCENOTE
PC6563,PC6584 = CH4224K1B01
(-1175 -4800) 0;
DISPLAY LEFT (-1175 -4800);
DISPLAY 1.021277 (-1175 -4800);
PAINT WHITE (-1175 -4800);
FORCENOTE
2ND SOURCE: INFENEON   BOM
(-1175 -4500) 0;
DISPLAY LEFT (-1175 -4500);
DISPLAY 1.021277 (-1175 -4500);
PAINT WHITE (-1175 -4500);
FORCENOTE
MAIN SOURCE: RENESAS    BOM
(-1175 -4225) 0;
DISPLAY LEFT (-1175 -4225);
DISPLAY 1.021277 (-1175 -4225);
PAINT WHITE (-1175 -4225);
FORCENOTE
PU6503,PU6504 = AL099390004 / ISL99390FRZ-TR5935
(-1175 -4300) 0;
DISPLAY LEFT (-1175 -4300);
DISPLAY 1.021277 (-1175 -4300);
PAINT WHITE (-1175 -4300);
FORCENOTE
PC6553_1,PC6576 = EMPTY
(-1175 -4875) 0;
DISPLAY LEFT (-1175 -4875);
DISPLAY 1.021277 (-1175 -4875);
PAINT WHITE (-1175 -4875);
FORCENOTE
BOM NOTE
(-2275 -4300) 0;
DISPLAY LEFT (-2275 -4300);
DISPLAY 1.021277 (-2275 -4300);
PAINT WHITE (-2275 -4300);
FORCENOTE
RI=3A
(800 -8900) 0;
DISPLAY LEFT (800 -8900);
DISPLAY 0.808511 (800 -8900);
PAINT PINK (800 -8900);
FORCENOTE
5*5.8
(800 -8950) 0;
DISPLAY LEFT (800 -8950);
DISPLAY 0.808511 (800 -8950);
PAINT PINK (800 -8950);
FORCENOTE
ESR=27M OHM
(800 -8848) 0;
DISPLAY LEFT (800 -8848);
DISPLAY 0.808511 (800 -8848);
PAINT PINK (800 -8848);
FORCENOTE
6.5*6.5*10
(-2125 -6750) 0;
DISPLAY LEFT (-2125 -6750);
DISPLAY 0.808511 (-2125 -6750);
PAINT PINK (-2125 -6750);
FORCENOTE
P0V9_CPU0_RT_2D_PHASE2
(-4725 -8025) 0;
DISPLAY LEFT (-4725 -8025);
DISPLAY 1.595745 (-4725 -8025);
PAINT WHITE (-4725 -8025);
FORCENOTE
ISAT = 13A @ 100C
(1025 -5750) 0;
DISPLAY LEFT (1025 -5750);
DISPLAY 1.021277 (1025 -5750);
PAINT PINK (1025 -5750);
FORCENOTE
DCR=0.17MOHM
(-2050 -9475) 0;
DISPLAY LEFT (-2050 -9475);
DISPLAY 0.808511 (-2050 -9475);
PAINT PINK (-2050 -9475);
FORCENOTE
PGL6312.121AHLT
(-2050 -9575) 0;
DISPLAY LEFT (-2050 -9575);
DISPLAY 0.808511 (-2050 -9575);
PAINT PINK (-2050 -9575);
FORCENOTE
ISAT=60 @100C
(-2050 -9525) 0;
DISPLAY LEFT (-2050 -9525);
DISPLAY 0.808511 (-2050 -9525);
PAINT PINK (-2050 -9525);
FORCENOTE
6.5*6.5*10
(-2025 -9650) 0;
DISPLAY LEFT (-2025 -9650);
DISPLAY 0.808511 (-2025 -9650);
PAINT PINK (-2025 -9650);
FORCENOTE
PGL6312.121AHLT
(-2150 -6675) 0;
DISPLAY LEFT (-2150 -6675);
DISPLAY 0.808511 (-2150 -6675);
PAINT PINK (-2150 -6675);
FORCENOTE
ISAT=60 @100C
(-2150 -6625) 0;
DISPLAY LEFT (-2150 -6625);
DISPLAY 0.808511 (-2150 -6625);
PAINT PINK (-2150 -6625);
FORCENOTE
DCR=0.17MOHM
(-2150 -6575) 0;
DISPLAY LEFT (-2150 -6575);
DISPLAY 0.808511 (-2150 -6575);
PAINT PINK (-2150 -6575);
FORCENOTE
DCR = 0.105M OHM
(1025 -5825) 0;
DISPLAY LEFT (1025 -5825);
DISPLAY 1.021277 (1025 -5825);
PAINT PINK (1025 -5825);
FORCENOTE
HCBS4545-101
(1025 -5585) 0;
DISPLAY LEFT (1025 -5585);
DISPLAY 1.021277 (1025 -5585);
PAINT PINK (1025 -5585);
FORCENOTE
4.5*4.5*4.5
(1025 -5650) 0;
DISPLAY LEFT (1025 -5650);
DISPLAY 1.021277 (1025 -5650);
PAINT PINK (1025 -5650);
FORCENOTE
5*5.8
(675 -6050) 0;
DISPLAY LEFT (675 -6050);
DISPLAY 0.808511 (675 -6050);
PAINT PINK (675 -6050);
FORCENOTE
RI=3A
(675 -6000) 0;
DISPLAY LEFT (675 -6000);
DISPLAY 0.808511 (675 -6000);
PAINT PINK (675 -6000);
FORCENOTE
ESR=27M OHM
(675 -5948) 0;
DISPLAY LEFT (675 -5948);
DISPLAY 0.808511 (675 -5948);
PAINT PINK (675 -5948);
FORCENOTE
P0V9_CPU0_RT_2D_PHASE1
(-4850 -5000) 0;
DISPLAY LEFT (-4850 -5000);
DISPLAY 1.595745 (-4850 -5000);
PAINT WHITE (-4850 -5000);
QUIT
